G04 ================== begin FILE IDENTIFICATION RECORD ==================*
G04 Layout Name:  9051_F0T_Panel_BD_Front_D_v02_20221209_1310.brd*
G04 Film Name:    sst.art*
G04 File Format:  Gerber RS274X*
G04 File Origin:  Cadence Allegro 17.2-S081*
G04 Origin Date:  Mon Dec 12 15:51:17 2022*
G04 *
G04 Layer:  DRAWING FORMAT/TITLE_BLOCK_A*
G04 Layer:  BOARD GEOMETRY/DESIGN_OUTLINE*
G04 Layer:  BOARD GEOMETRY/CUTOUT*
G04 Layer:  DRAWING FORMAT/TITLE_BLOCK*
G04 Layer:  MANUFACTURING/TP_TEXT_TOP*
G04 Layer:  REF DES/SILKSCREEN_TOP*
G04 Layer:  PACKAGE GEOMETRY/SILKSCREEN_TOP*
G04 Layer:  MANUFACTURING/PHOTOPLOT_OUTLINE*
G04 Layer:  DRAWING FORMAT/TITLE_DATA_SST*
G04 Layer:  BOARD GEOMETRY/SILKSCREEN_TOP*
G04 *
G04 Offset:    (0.00 0.00)*
G04 Mirror:    No*
G04 Mode:      Positive*
G04 Rotation:  0*
G04 FullContactRelief:  No*
G04 UndefLineWidth:     6.00*
G04 ================== end FILE IDENTIFICATION RECORD ====================*
%FSLAX25Y25*MOIN*%
%IR0*IPPOS*OFA0.00000B0.00000*MIA0B0*SFA1.00000B1.00000*%
%ADD10C,.006*%
G75*
%LPD*%
G75*
G36*
G01X13511Y128324D02*
X13505Y128325D01*
X13468D01*
X13458Y128326D01*
X13454D01*
X13426Y128328D01*
X13418D01*
X13415D01*
X13406Y128329D01*
X13382Y128330D01*
X13378D01*
X13370Y128331D01*
X13300Y128335D01*
X13235Y128346D01*
X12996Y128387D01*
X12887Y128427D01*
X12744Y128479D01*
X12736Y128482D01*
X12641Y128541D01*
X12589Y128574D01*
X12585Y128576D01*
X12580Y128580D01*
X12569Y128586D01*
X12553Y128596D01*
X12533Y128609D01*
X12518Y128618D01*
X12509Y128627D01*
X12452Y128684D01*
X12386Y128749D01*
X12341Y128794D01*
X12251Y128936D01*
X12205Y129007D01*
X12190Y129046D01*
X12141Y129172D01*
X12122Y129221D01*
X12108Y129257D01*
Y129258D01*
X12099Y129302D01*
X12096Y129317D01*
X12050Y129541D01*
X12044Y129621D01*
X12029Y129859D01*
X12044Y130207D01*
X12050Y130245D01*
X12096Y130584D01*
X12099Y130602D01*
X12108Y130653D01*
Y130655D01*
X12122Y130734D01*
X12141Y130842D01*
X12190Y131122D01*
X12205Y131207D01*
X12251Y131467D01*
X12341Y131983D01*
X12386Y132238D01*
X12452Y132610D01*
X12509Y132937D01*
X12518Y132989D01*
X12533Y133074D01*
X12553Y133189D01*
X12569Y133280D01*
X12580Y133341D01*
X12585Y133370D01*
X12589Y133372D01*
X13880D01*
X13884Y133370D01*
X13880Y133351D01*
X13879Y133342D01*
X13869Y133283D01*
X13853Y133197D01*
X13834Y133086D01*
X13828Y133054D01*
X13821Y133015D01*
X13811Y132954D01*
X13756Y132641D01*
X13725Y132465D01*
X13717Y132420D01*
X13704Y132346D01*
X13693Y132284D01*
X13603Y131772D01*
X13583Y131656D01*
X13574Y131607D01*
X13563Y131544D01*
X13538Y131401D01*
X13520Y131295D01*
X13511Y131248D01*
X13505Y131213D01*
X13468Y130998D01*
X13458Y130944D01*
X13454Y130920D01*
X13440Y130842D01*
X13426Y130764D01*
X13418Y130715D01*
X13415Y130698D01*
X13406Y130639D01*
X13382Y130465D01*
X13378Y130406D01*
X13370Y130263D01*
X13378Y130091D01*
X13382Y130072D01*
X13406Y129946D01*
X13415Y129924D01*
X13418Y129917D01*
X13426Y129895D01*
X13440Y129861D01*
X13454Y129826D01*
X13458Y129820D01*
X13468Y129806D01*
X13505Y129751D01*
X13511Y129743D01*
X13520Y129731D01*
X13538Y129714D01*
X13563Y129692D01*
X13574Y129682D01*
X13583Y129675D01*
X13603Y129657D01*
X13693Y129610D01*
X13704Y129604D01*
X13717Y129600D01*
X13725Y129598D01*
X13756Y129589D01*
X13811Y129573D01*
X13821Y129570D01*
X13828Y129569D01*
X13834Y129568D01*
X13853Y129566D01*
X13869Y129564D01*
X13879Y129562D01*
X13880D01*
X13884D01*
X13955Y129552D01*
X13988Y129554D01*
X14237Y129562D01*
X14245D01*
X14378Y129591D01*
X14460Y129621D01*
X14502Y129637D01*
X14615Y129702D01*
X14652Y129732D01*
X14703Y129775D01*
X14708Y129779D01*
X14719Y129788D01*
X14721Y129791D01*
X14734Y129806D01*
X14735Y129807D01*
X14751Y129826D01*
X14754Y129829D01*
X14759Y129835D01*
X14760Y129836D01*
X14812Y129897D01*
X14822Y129914D01*
X14895Y130030D01*
X14953Y130157D01*
X14968Y130189D01*
X15030Y130375D01*
X15081Y130590D01*
X15093Y130649D01*
X15096Y130669D01*
Y130670D01*
X15101Y130699D01*
X15112Y130759D01*
X15114Y130770D01*
X15127Y130846D01*
X15147Y130958D01*
X15170Y131091D01*
X15226Y131407D01*
X15289Y131768D01*
X15420Y132517D01*
X15473Y132820D01*
X15479Y132851D01*
X15526Y133123D01*
X15544Y133227D01*
X15558Y133306D01*
X15567Y133355D01*
X15570Y133372D01*
X16869D01*
X16868Y133358D01*
X16856Y133289D01*
X16855Y133286D01*
X16833Y133160D01*
X16802Y132984D01*
X16785Y132887D01*
X16764Y132766D01*
X16719Y132511D01*
X16669Y132226D01*
X16667Y132216D01*
X16557Y131587D01*
X16515Y131350D01*
X16436Y130900D01*
X16341Y130361D01*
X16315Y130213D01*
X16203Y129575D01*
X16153Y129289D01*
X16108Y129034D01*
X16070Y128816D01*
X16039Y128641D01*
X16017Y128514D01*
X16004Y128442D01*
X16001Y128428D01*
X14703D01*
X14708Y128458D01*
X14719Y128520D01*
X14721Y128532D01*
X14734Y128611D01*
X14735Y128613D01*
X14751Y128706D01*
X14754Y128722D01*
X14759Y128754D01*
X14760Y128757D01*
X14759D01*
X14754Y128752D01*
X14751Y128750D01*
X14735Y128736D01*
X14734D01*
X14721Y128725D01*
X14719Y128724D01*
X14708Y128715D01*
X14703Y128711D01*
X14652Y128672D01*
X14615Y128649D01*
X14502Y128579D01*
X14460Y128553D01*
X14378Y128516D01*
X14245Y128456D01*
X14237Y128453D01*
X13988Y128378D01*
X13955Y128372D01*
X13884Y128361D01*
X13880Y128360D01*
X13879D01*
X13869Y128358D01*
X13853Y128356D01*
X13834Y128352D01*
X13828D01*
X13821Y128350D01*
X13811Y128349D01*
X13756Y128340D01*
X13725Y128335D01*
X13717Y128333D01*
X13704D01*
X13693Y128332D01*
X13603Y128327D01*
X13583Y128326D01*
X13574Y128325D01*
X13563D01*
X13538Y128324D01*
X13511D01*
G37*
G36*
G01X10729Y127500D02*
X10719Y127502D01*
X10670Y127522D01*
X10630Y127538D01*
X10582Y127557D01*
X10516Y127583D01*
X10462Y127604D01*
X10430Y127617D01*
X10409Y127625D01*
X10253Y127686D01*
X10209Y127704D01*
X10194Y127709D01*
X10167Y127720D01*
X10150Y127727D01*
X9951Y127804D01*
X9944Y127806D01*
X9943Y127807D01*
X9923Y127815D01*
X9920D01*
X9889Y127828D01*
X9888D01*
X9883Y127830D01*
X9841Y127846D01*
X9832Y127850D01*
X9788Y127867D01*
X9782Y127869D01*
X9768Y127874D01*
X9692Y127903D01*
X9627Y127928D01*
X9605Y127936D01*
X9592Y127941D01*
X9533Y127963D01*
X9507Y127972D01*
X9431Y128001D01*
X9428Y128002D01*
X9400Y128013D01*
X9313Y128044D01*
X9283Y128054D01*
X9281Y128055D01*
X9189Y128088D01*
X9157Y128099D01*
X9132Y128109D01*
X9056Y128134D01*
X9025Y128144D01*
X9021Y128145D01*
X8953Y128164D01*
X8944Y128167D01*
X8921Y128170D01*
X8894D01*
X8886Y128171D01*
X8828D01*
X8763Y128173D01*
X8740D01*
X8610Y128177D01*
X8606D01*
X8590D01*
X8570Y128178D01*
X8522Y128182D01*
X8457Y128187D01*
X8441Y128188D01*
X8434Y128189D01*
X8356Y128195D01*
X8298Y128200D01*
X8280Y128201D01*
X8161Y128211D01*
X8126Y128214D01*
X8090Y128217D01*
X8026Y128228D01*
X7978Y128235D01*
X7965Y128238D01*
X7893Y128250D01*
X7837Y128259D01*
X7765Y128272D01*
X7703Y128282D01*
X7654Y128291D01*
X7641Y128294D01*
X7603Y128305D01*
X7578Y128312D01*
X7524Y128327D01*
X7413Y128358D01*
X7356Y128375D01*
X7312Y128387D01*
X7268Y128399D01*
X7259Y128402D01*
X7258D01*
X7219Y128418D01*
X7174Y128437D01*
X7138Y128453D01*
X7101Y128468D01*
X7068Y128483D01*
X7040Y128494D01*
X7011Y128507D01*
X6991Y128515D01*
X6969Y128524D01*
X6962Y128528D01*
X6957Y128530D01*
X6941Y128536D01*
X6936Y128538D01*
X6930Y128541D01*
X6902Y128553D01*
X6684Y128683D01*
X6582Y128745D01*
X6435Y128865D01*
X6294Y128980D01*
X6215Y129068D01*
X6037Y129266D01*
X6024Y129289D01*
X5862Y129550D01*
X5837Y129589D01*
X5730Y129842D01*
X5694Y129924D01*
X5627Y130157D01*
X5598Y130255D01*
X5554Y130489D01*
X5541Y130562D01*
X5512Y130820D01*
X5511Y130828D01*
X5502Y131007D01*
X5501Y131034D01*
X5500Y131087D01*
Y131109D01*
Y131157D01*
X5501Y131181D01*
X5502Y131230D01*
X5511Y131363D01*
X5512Y131375D01*
X5541Y131570D01*
X5554Y131663D01*
X5598Y131836D01*
X5627Y131947D01*
X5694Y132129D01*
X5730Y132224D01*
X5837Y132440D01*
X5862Y132489D01*
X6024Y132740D01*
X6037Y132757D01*
X6215Y132975D01*
X6294Y133053D01*
X6435Y133190D01*
X6582Y133304D01*
X6684Y133382D01*
X6902Y133513D01*
X6930Y133530D01*
X6936Y133533D01*
X6941Y133537D01*
X6957Y133546D01*
X6962Y133549D01*
X6969Y133552D01*
X6991Y133562D01*
X7011Y133571D01*
X7040Y133584D01*
X7068Y133597D01*
X7101Y133611D01*
X7138Y133628D01*
X7174Y133644D01*
X7219Y133665D01*
X7258Y133682D01*
X7259Y133683D01*
X7268Y133687D01*
X7312Y133700D01*
X7356Y133715D01*
X7413Y133733D01*
X7462Y133748D01*
X7524Y133768D01*
X7578Y133785D01*
X7603Y133793D01*
X7641Y133800D01*
X7654Y133803D01*
X7703Y133813D01*
X7765Y133825D01*
X7837Y133839D01*
X7893Y133850D01*
X7965Y133864D01*
X7978Y133865D01*
X8026Y133869D01*
X8090Y133875D01*
X8126Y133878D01*
X8161Y133881D01*
X8280Y133891D01*
X8298Y133893D01*
X8356Y133898D01*
X8434Y133899D01*
X8441Y133900D01*
X8457D01*
X8522D01*
X8570Y133899D01*
X8590D01*
X8606Y133898D01*
X8610D01*
X8740Y133889D01*
X8763Y133887D01*
X8828Y133882D01*
X8886Y133878D01*
X8894Y133877D01*
X8913Y133876D01*
X8921Y133875D01*
X8944Y133873D01*
X8953Y133872D01*
X9021Y133861D01*
X9025Y133860D01*
X9056Y133855D01*
X9132Y133841D01*
X9157Y133837D01*
X9189Y133832D01*
X9281Y133816D01*
X9283Y133815D01*
X9313Y133806D01*
X9400Y133782D01*
X9428Y133774D01*
X9431Y133773D01*
X9507Y133751D01*
X9533Y133744D01*
X9592Y133727D01*
X9605Y133722D01*
X9627Y133713D01*
X9692Y133686D01*
X9710Y133679D01*
X9768Y133655D01*
X9782Y133650D01*
X9788Y133647D01*
X9832Y133629D01*
X9841Y133626D01*
X9883Y133609D01*
X9888Y133606D01*
X9889D01*
X9920Y133589D01*
X9923Y133587D01*
X9943Y133576D01*
X9944D01*
X9951Y133572D01*
X10150Y133463D01*
X10167Y133454D01*
X10194Y133435D01*
X10209Y133424D01*
X10253Y133393D01*
X10409Y133283D01*
X10430Y133268D01*
X10462Y133240D01*
X10516Y133192D01*
X10582Y133132D01*
X10630Y133090D01*
X10670Y133054D01*
X10687Y133039D01*
X10719Y133000D01*
X10729Y132988D01*
X10786Y132917D01*
X10791Y132911D01*
X10885Y132796D01*
X10918Y132756D01*
X10930Y132741D01*
X11006Y132608D01*
X11112Y132424D01*
X11143Y132348D01*
X11177Y132263D01*
X11241Y132107D01*
X11254Y132059D01*
X11299Y131897D01*
X11325Y131805D01*
X11371Y131553D01*
X11374Y131539D01*
Y131535D01*
X11397Y131315D01*
X11401Y131228D01*
X11402Y131201D01*
Y131192D01*
Y131155D01*
Y131118D01*
X11401Y131108D01*
X11397Y131038D01*
X11374Y130650D01*
Y130641D01*
X11371Y130625D01*
X11325Y130359D01*
X11299Y130209D01*
X11254Y130065D01*
X11241Y130022D01*
X11177Y129821D01*
X11143Y129752D01*
X11112Y129689D01*
X11006Y129475D01*
X10930Y129369D01*
X10918Y129352D01*
X10885Y129307D01*
X10791Y129176D01*
X10786Y129169D01*
X10729Y129113D01*
X10719Y129103D01*
X10687Y129072D01*
X10670Y129055D01*
X10630Y129015D01*
X10582Y128968D01*
X10516Y128902D01*
X10462Y128864D01*
X10430Y128841D01*
X10409Y128826D01*
X10253Y128715D01*
X10209Y128683D01*
X10194Y128672D01*
X10209Y128661D01*
X10253Y128630D01*
X10409Y128520D01*
X10430Y128504D01*
X10462Y128482D01*
X10516Y128444D01*
X10582Y128396D01*
X10630Y128363D01*
X10670Y128334D01*
X10687Y128322D01*
X10719Y128300D01*
X10729Y128293D01*
X10786Y128252D01*
X10791Y128248D01*
X10885Y128182D01*
X10918Y128159D01*
X10930Y128150D01*
X11006Y128096D01*
X11112Y128021D01*
X11143Y127999D01*
X11177Y127975D01*
X11241Y127930D01*
X11254Y127921D01*
X11299Y127889D01*
X11325Y127870D01*
X11371Y127838D01*
X11374Y127836D01*
Y127835D01*
X11397Y127820D01*
X11401Y127817D01*
X11402Y127816D01*
X11408Y127812D01*
X11517Y127735D01*
X11539Y127720D01*
X11545Y127715D01*
X11551Y127710D01*
X11545Y127709D01*
X11539Y127707D01*
X11517Y127701D01*
X11408Y127674D01*
X11402Y127672D01*
X11401D01*
X11397Y127671D01*
X11374Y127665D01*
X11371Y127664D01*
X11325Y127652D01*
X11299Y127646D01*
X11254Y127634D01*
X11241Y127631D01*
X11177Y127615D01*
X11143Y127606D01*
X11112Y127598D01*
X11006Y127571D01*
X10930Y127552D01*
X10918Y127548D01*
X10885Y127540D01*
X10791Y127516D01*
X10786Y127515D01*
X10729Y127500D01*
G37*
G36*
G01X32413Y128324D02*
X32405Y128325D01*
X32394D01*
X32355Y128326D01*
X32343D01*
X32331Y128328D01*
X32304Y128330D01*
X32279Y128333D01*
X32262Y128335D01*
X32248Y128336D01*
X32239Y128337D01*
X32228Y128338D01*
X32209Y128340D01*
X32203Y128341D01*
X32190Y128342D01*
X32186Y128343D01*
X32180D01*
X32179D01*
X32175Y128344D01*
X32138Y128347D01*
X32134Y128348D01*
X32120Y128349D01*
X32106Y128351D01*
X32090Y128352D01*
X32069Y128355D01*
X32055Y128358D01*
X32049Y128359D01*
X31949Y128384D01*
X31868Y128404D01*
X31854Y128407D01*
X31829Y128413D01*
X31820Y128415D01*
X31819Y128416D01*
X31808Y128418D01*
X31798Y128422D01*
X31796Y128423D01*
X31795Y128424D01*
X31578Y128514D01*
X31568Y128518D01*
X31359Y128650D01*
X31352Y128654D01*
X31174Y128823D01*
X31169Y128827D01*
X31028Y129030D01*
X31023Y129037D01*
X30924Y129274D01*
X30920Y129285D01*
X30867Y129565D01*
X30866Y129570D01*
X30867Y129895D01*
X30920Y130209D01*
X30924Y130235D01*
X31023Y130522D01*
X31028Y130536D01*
X31169Y130794D01*
X31174Y130802D01*
X31352Y131028D01*
X31359Y131035D01*
X31568Y131224D01*
X31578Y131234D01*
X31795Y131377D01*
X31796Y131378D01*
X31798Y131380D01*
X31808Y131386D01*
X31819Y131393D01*
X31820Y131394D01*
X31829Y131399D01*
X31854Y131411D01*
X31868Y131418D01*
X31949Y131456D01*
X32049Y131504D01*
X32055Y131507D01*
X32069Y131513D01*
X32090Y131523D01*
X32106Y131531D01*
X32120Y131535D01*
X32134Y131540D01*
X32138Y131541D01*
X32175Y131553D01*
X32179Y131554D01*
X32180Y131555D01*
X32186Y131557D01*
X32190Y131558D01*
X32203Y131562D01*
X32209Y131565D01*
X32228Y131570D01*
X32239Y131574D01*
X32248Y131577D01*
X32262Y131582D01*
X32279Y131587D01*
X32304Y131595D01*
X32331Y131604D01*
X32343Y131608D01*
X32355Y131612D01*
X32394Y131624D01*
X32405Y131628D01*
X32413Y131630D01*
X32420Y131631D01*
X32456Y131638D01*
X32470Y131641D01*
X32479Y131643D01*
X32522Y131652D01*
X32526D01*
X32553Y131658D01*
X32559Y131659D01*
X32634Y131674D01*
X32661Y131680D01*
X32665D01*
X32722Y131692D01*
X32723D01*
X32778Y131697D01*
X32785Y131698D01*
X32790D01*
X32819Y131700D01*
X32839Y131702D01*
X32889Y131707D01*
X32921Y131710D01*
X32934Y131711D01*
X32986Y131716D01*
X33032Y131720D01*
X33055Y131722D01*
X33058D01*
X33138Y131724D01*
X33140D01*
X33172D01*
X33202D01*
X33234D01*
X33269Y131723D01*
X33323Y131719D01*
X33346Y131718D01*
X33363Y131717D01*
X33411Y131713D01*
X33478Y131708D01*
X33504Y131706D01*
X33510D01*
X33535Y131702D01*
X33558Y131698D01*
X33565Y131696D01*
X33579Y131694D01*
X33596Y131691D01*
X33603Y131690D01*
X33610Y131689D01*
X33611D01*
X33615Y131688D01*
X33616D01*
X33627Y131686D01*
X33642Y131683D01*
X33674Y131678D01*
X33697Y131674D01*
X33714Y131671D01*
X33724Y131668D01*
X33751Y131660D01*
X33756Y131659D01*
X33793Y131648D01*
X33804Y131645D01*
X33812Y131643D01*
X33813D01*
X33818Y131641D01*
X33826Y131639D01*
X33835Y131636D01*
X33847Y131633D01*
X33872Y131626D01*
X33885Y131622D01*
X33894Y131618D01*
X33896D01*
X33906Y131613D01*
X33915Y131610D01*
X33920Y131608D01*
X33922Y131607D01*
X33929Y131604D01*
X33979Y131584D01*
X34026Y131565D01*
X34028Y131564D01*
X34046Y131555D01*
X34088Y131533D01*
X34102Y131527D01*
Y131531D01*
X34110Y131574D01*
X34133Y131704D01*
X34135Y131715D01*
X34143Y131763D01*
X34145Y131772D01*
X34156Y131867D01*
X34145Y131957D01*
X34143Y131969D01*
X34135Y132043D01*
X34133Y132058D01*
X34110Y132101D01*
X34102Y132115D01*
Y132116D01*
X34088Y132141D01*
X34046Y132217D01*
X34028Y132235D01*
X34026Y132236D01*
X33979Y132281D01*
X33929Y132311D01*
X33922Y132316D01*
X33920Y132317D01*
X33915Y132320D01*
X33906Y132326D01*
X33896Y132332D01*
X33894Y132333D01*
X33885Y132337D01*
X33872Y132341D01*
X33847Y132351D01*
X33835Y132355D01*
X33826Y132359D01*
X33818Y132362D01*
X33813Y132363D01*
Y132364D01*
X33812D01*
X33804Y132367D01*
X33793Y132371D01*
X33756Y132378D01*
X33751Y132380D01*
X33724Y132385D01*
X33714Y132387D01*
X33697Y132390D01*
X33674Y132395D01*
X33642Y132396D01*
X33627Y132397D01*
X33616Y132398D01*
X33615D01*
X33610D01*
X33603D01*
X33596Y132399D01*
X33579Y132400D01*
X33565D01*
X33558Y132401D01*
X33535Y132402D01*
X33510D01*
X33504D01*
X33478Y132401D01*
X33411Y132400D01*
X33363Y132399D01*
X33346Y132398D01*
X33323Y132396D01*
X33269Y132391D01*
X33234Y132389D01*
X33202Y132386D01*
X33185Y132385D01*
X33183D01*
X33172Y132384D01*
X33140Y132382D01*
X33138Y132381D01*
X33058Y132375D01*
X33055Y132374D01*
X33032Y132370D01*
X32986Y132361D01*
X32934Y132352D01*
X32921Y132350D01*
X32889Y132344D01*
X32839Y132334D01*
X32819Y132330D01*
X32790Y132325D01*
X32785Y132324D01*
X32778Y132322D01*
X32723Y132305D01*
X32722D01*
X32665Y132287D01*
X32661Y132286D01*
X32634Y132278D01*
X32559Y132254D01*
X32553Y132252D01*
X32526Y132244D01*
X32522Y132243D01*
X32479Y132224D01*
X32470Y132221D01*
X32456Y132215D01*
X32420Y132200D01*
X32413Y132197D01*
Y132196D01*
X32405Y132193D01*
X32394Y132189D01*
X32355Y132172D01*
X32343Y132167D01*
X32331Y132162D01*
X32304Y132151D01*
X32279Y132140D01*
X32262Y132133D01*
X32248Y132127D01*
X32239Y132122D01*
X32228Y132118D01*
X32209Y132109D01*
X32203Y132105D01*
X32190Y132099D01*
X32186Y132098D01*
X32180Y132094D01*
X32179D01*
X32175Y132092D01*
X32138Y132074D01*
X32134D01*
X32120Y132111D01*
X32106Y132150D01*
X32090Y132191D01*
X32069Y132249D01*
X32055Y132284D01*
X32049Y132300D01*
X31949Y132567D01*
X31868Y132781D01*
X31854Y132819D01*
X31829Y132886D01*
X31820Y132907D01*
X31819Y132911D01*
X31808Y132941D01*
X31798Y132966D01*
X31796Y132971D01*
X31795Y132976D01*
X31796Y132977D01*
X31798Y132978D01*
X31808Y132983D01*
X31819Y132989D01*
X31820Y132990D01*
X31829Y132994D01*
X31854Y133007D01*
X31868Y133014D01*
X31949Y133054D01*
X32049Y133103D01*
X32055Y133106D01*
X32069Y133111D01*
X32090Y133120D01*
X32106Y133127D01*
X32134Y133139D01*
X32138Y133141D01*
X32175Y133156D01*
X32179Y133158D01*
X32180D01*
X32186Y133161D01*
X32190Y133163D01*
X32203Y133168D01*
X32209Y133171D01*
X32228Y133179D01*
X32239Y133183D01*
X32248Y133187D01*
X32262Y133193D01*
X32279Y133200D01*
X32304Y133211D01*
X32331Y133222D01*
X32343Y133227D01*
X32355Y133232D01*
X32394Y133248D01*
X32405Y133253D01*
X32413Y133256D01*
X32420Y133259D01*
X32456Y133270D01*
X32470Y133274D01*
X32479Y133277D01*
X32522Y133291D01*
X32526Y133292D01*
X32553Y133300D01*
X32559Y133302D01*
X32634Y133324D01*
X32661Y133333D01*
X32665Y133334D01*
X32722Y133352D01*
X32723D01*
X32778Y133368D01*
X32785Y133370D01*
X32790Y133372D01*
X32819Y133377D01*
X32839Y133381D01*
X32889Y133390D01*
X32921Y133396D01*
X32934Y133398D01*
X32986Y133408D01*
X33032Y133416D01*
X33055Y133420D01*
X33058Y133421D01*
X33138Y133435D01*
X33140Y133436D01*
X33172Y133442D01*
X33183Y133443D01*
X33185Y133444D01*
X33202Y133445D01*
X33234Y133447D01*
X33269Y133450D01*
X33323Y133454D01*
X33346Y133455D01*
X33363Y133456D01*
X33411Y133459D01*
X33478Y133464D01*
X33504Y133466D01*
X33510D01*
X33535Y133468D01*
X33558Y133470D01*
X33565D01*
X33579Y133471D01*
X33596Y133472D01*
X33603Y133473D01*
X33610D01*
X33611D01*
X33615Y133474D01*
X33616D01*
X33627D01*
X33642D01*
X33674Y133475D01*
X33697D01*
X33714D01*
X33724D01*
X33751Y133476D01*
X33756Y133475D01*
X33793Y133474D01*
X33804D01*
X33812D01*
X33813D01*
X33818Y133473D01*
X33826D01*
X33835D01*
X33847Y133472D01*
X33872D01*
X33885Y133471D01*
X33894D01*
X33896D01*
X33906Y133470D01*
X33915D01*
X33920D01*
X33929D01*
X33979Y133464D01*
X34026Y133458D01*
X34028D01*
X34046Y133456D01*
X34088Y133451D01*
X34102Y133449D01*
X34110Y133448D01*
X34133Y133446D01*
X34135Y133445D01*
X34143Y133444D01*
X34145D01*
X34156Y133443D01*
X34260Y133430D01*
X34418Y133390D01*
X34557Y133354D01*
X34595Y133337D01*
X34738Y133275D01*
X34817Y133241D01*
X34831Y133232D01*
X34858Y133213D01*
X34865Y133208D01*
X34880Y133198D01*
X34902Y133183D01*
X34929Y133165D01*
X34962Y133143D01*
X34998Y133118D01*
X35037Y133092D01*
X35081Y133047D01*
X35215Y132909D01*
X35255Y132843D01*
X35332Y132717D01*
X35348Y132692D01*
X35365Y132641D01*
X35393Y132559D01*
X35415Y132495D01*
X35431Y132451D01*
X35434Y132442D01*
X35438Y132407D01*
X35439Y132403D01*
X35442Y132376D01*
X35455Y132281D01*
X35470Y132159D01*
X35455Y131846D01*
X35442Y131763D01*
X35439Y131743D01*
X35438Y131739D01*
X35434Y131714D01*
X35431Y131696D01*
X35415Y131609D01*
X35393Y131483D01*
X35365Y131323D01*
X35348Y131222D01*
X35332Y131135D01*
X35255Y130694D01*
X35215Y130462D01*
X35081Y129700D01*
X35037Y129448D01*
X34998Y129230D01*
X34962Y129020D01*
X34929Y128835D01*
X34902Y128677D01*
X34880Y128554D01*
X34865Y128470D01*
X34858Y128430D01*
X34831Y128428D01*
X33558D01*
X33565Y128463D01*
X33579Y128547D01*
X33596Y128642D01*
X33603Y128683D01*
X33610Y128723D01*
X33611Y128728D01*
X33615Y128751D01*
X33616Y128757D01*
X33615D01*
X33611Y128753D01*
X33610Y128752D01*
X33603Y128746D01*
X33596Y128741D01*
X33579Y128729D01*
X33565Y128718D01*
X33558Y128714D01*
X33535Y128697D01*
X33510Y128679D01*
X33504Y128674D01*
X33478Y128656D01*
X33411Y128607D01*
X33363Y128582D01*
X33346Y128572D01*
X33323Y128560D01*
X33269Y128532D01*
X33234Y128514D01*
X33202Y128496D01*
X33185Y128488D01*
X33183Y128487D01*
X33172Y128483D01*
X33140Y128472D01*
X33138Y128471D01*
X33058Y128442D01*
X33055Y128441D01*
X33032Y128432D01*
X32986Y128416D01*
X32934Y128397D01*
X32921Y128394D01*
X32889Y128387D01*
X32839Y128377D01*
X32819Y128373D01*
X32790Y128367D01*
X32785Y128366D01*
X32778Y128365D01*
X32723Y128353D01*
X32722D01*
X32665Y128341D01*
X32661Y128340D01*
X32634Y128337D01*
X32559Y128330D01*
X32553D01*
X32526Y128327D01*
X32522D01*
X32479Y128326D01*
X32470Y128325D01*
X32456D01*
X32420D01*
X32413Y128324D01*
G37*
G36*
G01X21767Y128428D02*
X21763Y128432D01*
X21767Y128449D01*
X21772Y128483D01*
X21792Y128593D01*
X21819Y128746D01*
X21820Y128752D01*
X21856Y128957D01*
X21898Y129200D01*
X21922Y129336D01*
X21947Y129476D01*
X22000Y129779D01*
X22064Y130146D01*
X22116Y130439D01*
X22356Y131808D01*
X22411Y132124D01*
X22413Y132131D01*
X22463Y132419D01*
X22510Y132685D01*
X22550Y132916D01*
X22583Y133106D01*
X22609Y133250D01*
X22625Y133341D01*
X22630Y133372D01*
X23917D01*
X23924D01*
X23928Y133371D01*
X23930D01*
X23928Y133358D01*
X23924Y133339D01*
X23917Y133296D01*
X23915Y133289D01*
X23901Y133207D01*
X23885Y133119D01*
Y133114D01*
X23881Y133096D01*
X23874Y133057D01*
X23872Y133043D01*
X23874Y133044D01*
X23881Y133051D01*
X23885Y133054D01*
X23901Y133067D01*
X23915Y133079D01*
X23917Y133080D01*
X23924Y133086D01*
X23928Y133089D01*
X23930Y133090D01*
X23982Y133125D01*
X24092Y133201D01*
X24105Y133209D01*
X24212Y133263D01*
X24318Y133317D01*
X24482Y133374D01*
X24559Y133400D01*
X24747Y133440D01*
X24750Y133441D01*
X24758Y133442D01*
X24769Y133444D01*
X24772Y133445D01*
X24779Y133446D01*
X24790Y133449D01*
X24823Y133456D01*
X24837Y133457D01*
X24867Y133459D01*
X24891Y133461D01*
X24896D01*
X24998Y133468D01*
X25026Y133470D01*
X25087Y133474D01*
X25089D01*
X25106Y133476D01*
X25144Y133473D01*
X25158Y133472D01*
X25159D01*
X25167Y133471D01*
X25186Y133470D01*
X25202Y133469D01*
X25212Y133468D01*
X25217D01*
X25220D01*
X25230Y133467D01*
X25246Y133466D01*
X25256Y133465D01*
X25261D01*
X25439Y133453D01*
X25519Y133435D01*
X25692Y133394D01*
X25728Y133386D01*
X25844Y133335D01*
X25962Y133283D01*
X25974Y133278D01*
X26033Y133234D01*
X26049Y133222D01*
X26056Y133217D01*
X26069Y133208D01*
X26086Y133195D01*
X26107Y133180D01*
X26161Y133140D01*
X26178Y133128D01*
X26224Y133074D01*
X26292Y132996D01*
X26341Y132939D01*
X26360Y132904D01*
X26423Y132789D01*
X26464Y132713D01*
X26476Y132674D01*
X26498Y132607D01*
X26515Y132553D01*
X26528Y132514D01*
X26535Y132492D01*
X26536Y132488D01*
X26537D01*
X26539Y132479D01*
X26548Y132454D01*
Y132452D01*
X26575Y132280D01*
X26594Y132156D01*
X26602Y131829D01*
X26594Y131718D01*
X26575Y131470D01*
X26548Y131283D01*
Y131280D01*
X26539Y131232D01*
X26537Y131215D01*
X26536D01*
X26535Y131207D01*
X26528Y131167D01*
X26515Y131095D01*
X26498Y130996D01*
X26476Y130873D01*
X26464Y130802D01*
X26423Y130568D01*
X26360Y130209D01*
X26341Y130100D01*
X26292Y129822D01*
X26224Y129434D01*
X26178Y129171D01*
X26161Y129074D01*
X26107Y128770D01*
X26086Y128647D01*
X26069Y128548D01*
X26056Y128476D01*
X26049Y128436D01*
X26033Y128428D01*
X24747D01*
X24750Y128445D01*
X24758Y128494D01*
X24769Y128552D01*
X24772Y128572D01*
X24779Y128611D01*
X24790Y128675D01*
X24823Y128861D01*
X24837Y128944D01*
X24867Y129110D01*
X24891Y129249D01*
X24896Y129274D01*
X24998Y129854D01*
X25026Y130015D01*
X25087Y130362D01*
X25089Y130371D01*
X25106Y130473D01*
X25144Y130684D01*
X25158Y130768D01*
X25159Y130769D01*
X25167Y130816D01*
X25186Y130927D01*
X25202Y131013D01*
X25212Y131072D01*
Y131073D01*
X25217Y131100D01*
Y131102D01*
X25220Y131123D01*
X25230Y131183D01*
X25246Y131321D01*
X25256Y131406D01*
X25261Y131598D01*
X25256Y131654D01*
X25246Y131761D01*
X25230Y131825D01*
X25220Y131863D01*
X25217Y131878D01*
Y131879D01*
X25212Y131898D01*
X25202Y131920D01*
X25186Y131952D01*
X25167Y131992D01*
X25159Y132009D01*
X25158D01*
X25144Y132028D01*
X25106Y132073D01*
X25089Y132095D01*
X25087Y132097D01*
X25026Y132143D01*
X24998Y132163D01*
X24896Y132208D01*
X24891Y132210D01*
X24867Y132216D01*
X24837Y132223D01*
X24823Y132226D01*
X24790Y132234D01*
X24779Y132236D01*
X24772Y132238D01*
X24769Y132239D01*
X24758D01*
X24750D01*
X24747D01*
X24559Y132246D01*
X24482Y132249D01*
X24318Y132217D01*
X24212Y132197D01*
X24105Y132150D01*
X24092Y132145D01*
X23982Y132072D01*
X23930Y132024D01*
X23928Y132022D01*
X23924Y132019D01*
X23917Y132012D01*
X23915Y132011D01*
X23901Y131997D01*
X23885Y131983D01*
Y131982D01*
X23881Y131979D01*
X23874Y131970D01*
X23872Y131967D01*
X23844Y131932D01*
X23791Y131862D01*
X23727Y131747D01*
X23712Y131720D01*
X23643Y131552D01*
X23585Y131356D01*
X23575Y131309D01*
X23537Y131131D01*
X23534Y131113D01*
X23526Y131064D01*
X23512Y130985D01*
X23494Y130882D01*
X23446Y130609D01*
X23401Y130357D01*
X23387Y130276D01*
X23256Y129527D01*
X23192Y129167D01*
X23137Y128850D01*
X23113Y128717D01*
X23093Y128605D01*
X23078Y128518D01*
X23068Y128458D01*
X23063Y128430D01*
X23059Y128428D01*
X21767D01*
G37*
G36*
G01X18484Y128324D02*
X18476Y128325D01*
X18465D01*
X18426Y128326D01*
X18414D01*
X18402Y128328D01*
X18376Y128330D01*
X18350Y128333D01*
X18334Y128335D01*
X18320Y128336D01*
X18310Y128337D01*
X18300Y128338D01*
X18281Y128340D01*
X18274Y128341D01*
X18261Y128342D01*
X18258Y128343D01*
X18252D01*
X18250D01*
X18247D01*
X18209Y128347D01*
X18206Y128348D01*
X18192Y128349D01*
X18177Y128351D01*
X18162Y128352D01*
X18140Y128355D01*
X18127Y128358D01*
X18121Y128359D01*
X18020Y128384D01*
X17940Y128404D01*
X17926Y128407D01*
X17900Y128413D01*
X17892Y128415D01*
X17891Y128416D01*
X17880Y128418D01*
X17870Y128422D01*
X17868Y128423D01*
X17867Y128424D01*
X17650Y128514D01*
X17639Y128518D01*
X17430Y128650D01*
X17424Y128654D01*
X17245Y128823D01*
X17241Y128827D01*
X17099Y129030D01*
X17094Y129037D01*
X16996Y129274D01*
X16991Y129285D01*
X16938Y129565D01*
X16937Y129570D01*
X16938Y129895D01*
X16991Y130209D01*
X16996Y130235D01*
X17094Y130522D01*
X17099Y130536D01*
X17241Y130794D01*
X17245Y130802D01*
X17424Y131028D01*
X17430Y131035D01*
X17639Y131224D01*
X17650Y131234D01*
X17867Y131377D01*
X17868Y131378D01*
X17870Y131380D01*
X17880Y131386D01*
X17891Y131393D01*
X17892Y131394D01*
X17900Y131399D01*
X17926Y131411D01*
X17940Y131418D01*
X18020Y131456D01*
X18121Y131504D01*
X18127Y131507D01*
X18140Y131513D01*
X18162Y131524D01*
X18177Y131531D01*
X18192Y131535D01*
X18206Y131540D01*
X18209Y131541D01*
X18247Y131554D01*
X18250Y131555D01*
X18252D01*
X18258Y131557D01*
X18274Y131563D01*
X18281Y131565D01*
X18300Y131571D01*
X18310Y131574D01*
X18320Y131577D01*
X18334Y131582D01*
X18350Y131587D01*
X18376Y131596D01*
X18402Y131604D01*
X18414Y131608D01*
X18426Y131612D01*
X18465Y131625D01*
X18476Y131628D01*
X18484Y131630D01*
X18485D01*
X18491Y131631D01*
X18527Y131639D01*
X18541Y131641D01*
X18551Y131643D01*
X18594Y131652D01*
X18597D01*
X18624Y131658D01*
X18630Y131659D01*
X18706Y131674D01*
X18733Y131680D01*
X18736D01*
X18794Y131692D01*
X18850Y131697D01*
X18856Y131698D01*
X18861D01*
X18890Y131700D01*
X18911Y131702D01*
X18960Y131707D01*
X18993Y131710D01*
X19006Y131711D01*
X19057Y131716D01*
X19102Y131720D01*
X19126Y131722D01*
X19130D01*
X19209Y131724D01*
X19211D01*
X19244D01*
X19272D01*
X19306D01*
X19339Y131723D01*
X19394Y131719D01*
X19418Y131718D01*
X19435Y131717D01*
X19482Y131713D01*
X19550Y131708D01*
X19575Y131706D01*
X19581D01*
X19607Y131702D01*
X19629Y131698D01*
X19635Y131697D01*
X19650Y131694D01*
X19667Y131691D01*
X19674Y131690D01*
X19682Y131689D01*
X19686Y131688D01*
X19687D01*
X19698Y131686D01*
X19713Y131683D01*
X19746Y131678D01*
X19768Y131674D01*
X19785Y131671D01*
X19796Y131668D01*
X19824Y131660D01*
X19828Y131659D01*
X19864Y131648D01*
X19876Y131645D01*
X19884Y131643D01*
X19885D01*
X19890Y131641D01*
X19898Y131639D01*
X19907Y131636D01*
X19918Y131633D01*
X19919D01*
X19944Y131626D01*
X19956Y131622D01*
X19966Y131618D01*
X19968D01*
X19978Y131613D01*
X19986Y131610D01*
X19991Y131608D01*
X19993Y131607D01*
X20001Y131604D01*
X20050Y131584D01*
X20098Y131565D01*
X20118Y131555D01*
X20160Y131533D01*
X20173Y131527D01*
X20174Y131531D01*
X20182Y131574D01*
X20204Y131706D01*
X20206Y131715D01*
X20215Y131763D01*
X20216Y131772D01*
X20227Y131867D01*
X20216Y131960D01*
X20215Y131972D01*
X20206Y132045D01*
X20204Y132058D01*
X20182Y132101D01*
X20174Y132115D01*
X20173Y132116D01*
X20160Y132141D01*
X20118Y132217D01*
X20098Y132236D01*
X20050Y132281D01*
X20001Y132311D01*
X19993Y132316D01*
X19991Y132317D01*
X19986Y132320D01*
X19978Y132325D01*
X19968Y132332D01*
X19966Y132333D01*
X19956Y132337D01*
X19944Y132341D01*
X19919Y132351D01*
X19918D01*
X19907Y132355D01*
X19898Y132359D01*
X19890Y132361D01*
X19885Y132363D01*
X19884Y132364D01*
X19876Y132367D01*
X19864Y132371D01*
X19828Y132378D01*
X19824Y132380D01*
X19796Y132385D01*
X19785Y132387D01*
X19768Y132390D01*
X19746Y132395D01*
X19713Y132396D01*
X19698Y132397D01*
X19687Y132398D01*
X19682D01*
X19674D01*
X19667Y132399D01*
X19650Y132400D01*
X19635D01*
X19629Y132401D01*
X19607Y132402D01*
X19581D01*
X19575D01*
X19550Y132401D01*
X19482Y132400D01*
X19435Y132399D01*
X19418Y132398D01*
X19394Y132396D01*
X19339Y132391D01*
X19306Y132389D01*
X19272Y132386D01*
X19257Y132385D01*
X19256D01*
X19253D01*
X19244Y132384D01*
X19211Y132382D01*
X19209Y132381D01*
X19130Y132375D01*
X19126Y132374D01*
X19102Y132370D01*
X19057Y132361D01*
X19006Y132352D01*
X18993Y132350D01*
X18960Y132344D01*
X18911Y132334D01*
X18890Y132330D01*
X18861Y132325D01*
X18856Y132324D01*
X18850Y132322D01*
X18794Y132305D01*
X18736Y132287D01*
X18733Y132286D01*
X18706Y132278D01*
X18630Y132254D01*
X18624Y132252D01*
X18597Y132244D01*
X18594Y132243D01*
X18551Y132224D01*
X18541Y132220D01*
X18527Y132215D01*
X18491Y132200D01*
X18485Y132196D01*
X18484D01*
X18476Y132193D01*
X18465Y132189D01*
X18426Y132172D01*
X18414Y132167D01*
X18402Y132162D01*
X18376Y132151D01*
X18350Y132140D01*
X18334Y132133D01*
X18320Y132127D01*
X18310Y132122D01*
X18300Y132117D01*
X18281Y132108D01*
X18274Y132105D01*
X18261Y132099D01*
X18258Y132097D01*
X18252Y132094D01*
X18250D01*
X18247Y132092D01*
X18209Y132074D01*
X18206D01*
X18192Y132111D01*
X18177Y132152D01*
X18162Y132191D01*
X18140Y132250D01*
X18127Y132285D01*
X18121Y132300D01*
X18020Y132567D01*
X17940Y132781D01*
X17926Y132819D01*
X17900Y132887D01*
X17892Y132907D01*
X17891Y132911D01*
X17880Y132941D01*
X17870Y132966D01*
X17868Y132971D01*
X17867Y132976D01*
X17868Y132977D01*
X17870Y132978D01*
X17880Y132983D01*
X17891Y132989D01*
X17892Y132990D01*
X17900Y132994D01*
X17926Y133007D01*
X17940Y133014D01*
X18020Y133054D01*
X18121Y133103D01*
X18127Y133106D01*
X18140Y133111D01*
X18162Y133121D01*
X18177Y133127D01*
X18192Y133133D01*
X18206Y133139D01*
X18209Y133141D01*
X18247Y133156D01*
X18250Y133158D01*
X18252D01*
X18258Y133161D01*
X18261Y133163D01*
X18274Y133168D01*
X18281Y133171D01*
X18300Y133179D01*
X18310Y133183D01*
X18320Y133187D01*
X18334Y133193D01*
X18350Y133200D01*
X18376Y133211D01*
X18402Y133222D01*
X18414Y133227D01*
X18426Y133232D01*
X18465Y133248D01*
X18476Y133253D01*
X18484Y133256D01*
X18485D01*
X18491Y133259D01*
X18527Y133270D01*
X18541Y133274D01*
X18551Y133277D01*
X18594Y133291D01*
X18597Y133292D01*
X18624Y133300D01*
X18630Y133302D01*
X18706Y133324D01*
X18733Y133333D01*
X18736Y133334D01*
X18794Y133352D01*
X18850Y133368D01*
X18856Y133370D01*
X18861Y133372D01*
X18890Y133377D01*
X18911Y133381D01*
X18960Y133390D01*
X18993Y133396D01*
X19006Y133398D01*
X19057Y133408D01*
X19102Y133416D01*
X19126Y133420D01*
X19130Y133421D01*
X19209Y133435D01*
X19211D01*
X19244Y133442D01*
X19253Y133443D01*
X19256Y133444D01*
X19257D01*
X19272Y133445D01*
X19306Y133447D01*
X19339Y133450D01*
X19394Y133454D01*
X19418Y133455D01*
X19435Y133456D01*
X19482Y133459D01*
X19550Y133464D01*
X19575Y133466D01*
X19581D01*
X19607Y133468D01*
X19629Y133470D01*
X19635D01*
X19650Y133471D01*
X19667Y133472D01*
X19674Y133473D01*
X19682D01*
X19686Y133474D01*
X19687D01*
X19698D01*
X19713D01*
X19746Y133475D01*
X19768D01*
X19785D01*
X19796D01*
X19824Y133476D01*
X19828Y133475D01*
X19864Y133474D01*
X19876D01*
X19884D01*
X19885D01*
X19890Y133473D01*
X19898D01*
X19907D01*
X19918Y133472D01*
X19919D01*
X19944D01*
X19956Y133471D01*
X19966D01*
X19968D01*
X19978Y133470D01*
X19986D01*
X19991D01*
X20001D01*
X20050Y133464D01*
X20098Y133458D01*
X20118Y133456D01*
X20160Y133451D01*
X20173Y133449D01*
X20174D01*
X20182Y133448D01*
X20204Y133446D01*
X20206D01*
X20215Y133444D01*
X20216D01*
X20227Y133443D01*
X20332Y133430D01*
X20489Y133390D01*
X20628Y133354D01*
X20666Y133337D01*
X20809Y133275D01*
X20888Y133241D01*
X20902Y133231D01*
X20930Y133213D01*
X20937Y133208D01*
X20952Y133198D01*
X20973Y133183D01*
X21001Y133165D01*
X21033Y133143D01*
X21070Y133118D01*
X21108Y133092D01*
X21152Y133046D01*
X21286Y132909D01*
X21327Y132843D01*
X21404Y132717D01*
X21419Y132692D01*
X21437Y132641D01*
X21465Y132559D01*
X21487Y132495D01*
X21502Y132451D01*
X21506Y132442D01*
X21510Y132407D01*
X21511Y132403D01*
X21514Y132376D01*
X21526Y132281D01*
X21542Y132159D01*
X21526Y131846D01*
X21514Y131763D01*
X21511Y131743D01*
X21510Y131739D01*
X21506Y131714D01*
X21502Y131696D01*
X21487Y131609D01*
X21465Y131483D01*
X21437Y131323D01*
X21419Y131222D01*
X21404Y131135D01*
X21327Y130694D01*
X21286Y130462D01*
X21152Y129700D01*
X21108Y129447D01*
X21070Y129230D01*
X21033Y129020D01*
X21001Y128835D01*
X20973Y128677D01*
X20952Y128554D01*
X20937Y128470D01*
X20930Y128430D01*
X20902Y128428D01*
X19629D01*
X19635Y128463D01*
X19650Y128547D01*
X19667Y128641D01*
X19674Y128683D01*
X19682Y128728D01*
X19686Y128751D01*
X19687Y128757D01*
X19686D01*
X19682Y128753D01*
X19674Y128746D01*
X19667Y128741D01*
X19650Y128729D01*
X19635Y128718D01*
X19629Y128714D01*
X19607Y128698D01*
X19581Y128679D01*
X19575Y128674D01*
X19550Y128656D01*
X19482Y128607D01*
X19435Y128582D01*
X19418Y128573D01*
X19394Y128560D01*
X19339Y128531D01*
X19306Y128513D01*
X19272Y128496D01*
X19257Y128488D01*
X19256D01*
X19253Y128487D01*
X19244Y128483D01*
X19211Y128471D01*
X19209Y128470D01*
X19130Y128442D01*
X19126Y128441D01*
X19102Y128432D01*
X19057Y128416D01*
X19006Y128397D01*
X18993Y128394D01*
X18960Y128387D01*
X18911Y128377D01*
X18890Y128373D01*
X18861Y128367D01*
X18856Y128366D01*
X18850Y128365D01*
X18794Y128353D01*
X18736Y128341D01*
X18733Y128340D01*
X18706Y128338D01*
X18630Y128330D01*
X18624D01*
X18597Y128327D01*
X18594D01*
X18551Y128326D01*
X18541Y128325D01*
X18527D01*
X18491D01*
X18485Y128324D01*
X18484D01*
G37*
G36*
G01X28764D02*
X28613Y128340D01*
X28569Y128344D01*
X28553Y128346D01*
X28543Y128347D01*
X28518Y128349D01*
X28482Y128353D01*
X28441Y128367D01*
X28400Y128381D01*
X28365Y128393D01*
X28339Y128401D01*
X28330Y128405D01*
X28294Y128417D01*
X28239Y128435D01*
X28200Y128461D01*
X28115Y128516D01*
X28111Y128519D01*
X28098Y128528D01*
X28080Y128539D01*
X28077Y128541D01*
X28051Y128558D01*
X28037Y128567D01*
X27986Y128624D01*
X27985D01*
X27916Y128701D01*
X27910Y128707D01*
X27878Y128744D01*
X27835Y128824D01*
X27769Y128948D01*
X27763Y128961D01*
X27743Y129033D01*
X27723Y129108D01*
X27710Y129156D01*
X27705Y129173D01*
X27701Y129190D01*
X27694Y129215D01*
X27674Y129500D01*
X27694Y129700D01*
X27701Y129768D01*
X27705Y129813D01*
X27710Y129839D01*
X27723Y129913D01*
X27743Y130028D01*
X27763Y130139D01*
X27769Y130178D01*
X27835Y130552D01*
X27878Y130794D01*
X27910Y130980D01*
X27916Y131011D01*
X27985Y131409D01*
X27986Y131410D01*
X28037Y131702D01*
X28051Y131783D01*
X28077Y131932D01*
X28080Y131945D01*
X28098Y132047D01*
X28111Y132122D01*
X28115Y132148D01*
X27286D01*
X27296Y132200D01*
X27320Y132339D01*
X27322Y132350D01*
X27354Y132535D01*
X27394Y132760D01*
X27416Y132884D01*
X27433Y132985D01*
X27468Y133181D01*
X27493Y133320D01*
X27502Y133372D01*
X28330D01*
X28339Y133427D01*
X28365Y133571D01*
X28400Y133774D01*
X28441Y134007D01*
X28482Y134241D01*
X28518Y134444D01*
X28543Y134589D01*
X28553Y134643D01*
X28569Y134650D01*
X28613Y134671D01*
X28764Y134740D01*
X28774Y134745D01*
X29000Y134849D01*
X29046Y134870D01*
X29065Y134879D01*
X29067D01*
Y134880D01*
X29070Y134881D01*
X29082Y134886D01*
X29098Y134894D01*
X29107Y134898D01*
X29121Y134904D01*
X29177Y134930D01*
X29241Y134959D01*
X29260Y134968D01*
X29305Y134989D01*
X29353Y135011D01*
X29361Y135015D01*
X29383Y135025D01*
X29400Y135033D01*
X29411Y135038D01*
X29415Y135040D01*
X29443Y135052D01*
X29466Y135063D01*
X29520Y135087D01*
X29601Y135125D01*
X29611Y135130D01*
X29615Y135132D01*
X29630Y135138D01*
X29633Y135140D01*
X29644Y135145D01*
X29661Y135152D01*
X29681Y135162D01*
X29682Y135163D01*
X29737Y135187D01*
X29746Y135192D01*
X29793Y135213D01*
X29798Y135216D01*
X29815Y135223D01*
X29823Y135227D01*
X29828Y135229D01*
X29841Y135235D01*
X29860Y135244D01*
X29889Y135257D01*
X29906Y135265D01*
X29915Y135269D01*
X29936Y135279D01*
X29951Y135286D01*
X29953Y135287D01*
X29956Y135288D01*
X29963Y135292D01*
X29967Y135293D01*
X29963Y135272D01*
X29956Y135230D01*
X29953Y135211D01*
X29951Y135203D01*
X29936Y135116D01*
X29915Y134993D01*
X29906Y134947D01*
X29889Y134847D01*
X29860Y134685D01*
X29841Y134577D01*
X29828Y134501D01*
X29823Y134474D01*
X29815Y134428D01*
X29798Y134333D01*
X29793Y134302D01*
X29746Y134035D01*
X29737Y133980D01*
X29682Y133672D01*
X29681Y133663D01*
X29661Y133550D01*
X29644Y133455D01*
X29633Y133394D01*
X29630Y133372D01*
X30816D01*
X30807Y133320D01*
X30783Y133181D01*
X30765Y133081D01*
X30748Y132985D01*
X30709Y132760D01*
X30669Y132535D01*
X30635Y132339D01*
X30631Y132314D01*
X30611Y132200D01*
X30602Y132148D01*
X29415D01*
X29411Y132126D01*
X29400Y132062D01*
X29383Y131965D01*
X29361Y131837D01*
X29353Y131793D01*
X29305Y131519D01*
X29260Y131263D01*
X29241Y131156D01*
Y131154D01*
X29177Y130790D01*
X29121Y130472D01*
X29107Y130392D01*
X29098Y130344D01*
X29082Y130246D01*
X29070Y130183D01*
X29067Y130165D01*
Y130161D01*
X29065Y130154D01*
X29046Y130004D01*
Y130000D01*
Y129869D01*
X29065Y129774D01*
X29067Y129769D01*
Y129766D01*
X29070Y129759D01*
X29082Y129738D01*
X29098Y129704D01*
X29107Y129687D01*
X29121Y129678D01*
X29177Y129639D01*
X29241Y129594D01*
X29260Y129592D01*
X29305Y129586D01*
X29353Y129580D01*
X29361Y129578D01*
X29383Y129575D01*
X29400Y129573D01*
X29411Y129572D01*
X29415Y129571D01*
X29443Y129568D01*
X29466Y129570D01*
X29520Y129577D01*
X29601Y129586D01*
X29611Y129587D01*
X29615Y129588D01*
X29630Y129593D01*
X29633Y129595D01*
X29644Y129599D01*
X29661Y129605D01*
X29681Y129612D01*
X29682Y129613D01*
X29737Y129633D01*
X29746Y129636D01*
X29793Y129653D01*
X29798Y129656D01*
X29815Y129666D01*
X29823Y129671D01*
X29828Y129674D01*
X29841Y129681D01*
X29860Y129692D01*
X29889Y129709D01*
X29906Y129718D01*
X29915Y129723D01*
X29936Y129736D01*
X29951Y129744D01*
X29953Y129745D01*
X29956Y129747D01*
X29963Y129752D01*
X29967Y129754D01*
X29996Y129770D01*
X30009Y129779D01*
X30033Y129796D01*
X30110Y129851D01*
X30177Y129898D01*
X30223Y129931D01*
X30225Y129932D01*
X30238Y129941D01*
X30243Y129945D01*
X30238Y129930D01*
X30225Y129888D01*
X30223Y129882D01*
X30177Y129739D01*
X30110Y129528D01*
X30033Y129285D01*
X30009Y129208D01*
X29996Y129168D01*
X29967Y129078D01*
X29963Y129066D01*
X29956Y129043D01*
X29953Y129032D01*
X29951Y129028D01*
X29936Y128980D01*
X29915Y128912D01*
X29906Y128887D01*
X29889Y128832D01*
X29860Y128743D01*
X29841Y128682D01*
X29828Y128641D01*
X29823Y128626D01*
X29815Y128621D01*
X29798Y128612D01*
X29793Y128609D01*
X29746Y128583D01*
X29737Y128577D01*
X29682Y128547D01*
X29681Y128546D01*
X29661Y128535D01*
X29644Y128526D01*
X29633Y128520D01*
X29630Y128518D01*
X29615Y128509D01*
X29611Y128507D01*
X29601Y128504D01*
X29520Y128473D01*
X29466Y128454D01*
X29443Y128445D01*
X29415Y128435D01*
X29411Y128433D01*
X29400Y128429D01*
X29383Y128423D01*
X29361Y128415D01*
X29353Y128411D01*
X29305Y128401D01*
X29260Y128391D01*
X29241Y128387D01*
X29177Y128372D01*
X29121Y128360D01*
X29107Y128357D01*
X29098Y128355D01*
X29082Y128351D01*
X29070Y128349D01*
X29067Y128348D01*
X29065D01*
X29046Y128346D01*
X29000Y128343D01*
X28774Y128325D01*
X28764Y128324D01*
G37*
G36*
G01X31456Y206838D02*
X27456D01*
X29456Y202838D01*
X31456Y206838D01*
G37*
G36*
G01X38468Y248200D02*
X34468D01*
X36468Y244200D01*
X38468Y248200D01*
G37*
G36*
G01X44850Y92926D02*
X46585Y92059D01*
X44850Y91192D01*
Y92926D01*
G37*
G36*
G01X77453Y82450D02*
X78703Y84950D01*
X76203D01*
X77453Y82450D01*
G37*
G36*
G01X96508Y103181D02*
X92508D01*
X94508Y99181D01*
X96508Y103181D01*
G37*
G36*
G01X115316Y23716D02*
Y19716D01*
X119316Y21716D01*
X115316Y23716D01*
G37*
G36*
G01X120053Y99625D02*
X118053Y98625D01*
Y100625D01*
X120053Y99625D01*
G37*
G36*
G01X100450Y107547D02*
X102950Y106297D01*
Y108797D01*
X100450Y107547D01*
G37*
G36*
G01X116371Y121269D02*
X118429Y120240D01*
X116371Y119211D01*
Y121269D01*
G37*
G36*
G01X115584Y286055D02*
Y282055D01*
X111584Y284055D01*
X115584Y286055D01*
G37*
G36*
G01X125877Y72974D02*
X123225Y72091D01*
X124993Y70323D01*
X125877Y72974D01*
G37*
G36*
G01X380195Y95999D02*
X383195Y101999D01*
X377195D01*
X380195Y95999D01*
G37*
G36*
G01X370195Y244619D02*
X367195Y238619D01*
X373195D01*
X370195Y244619D01*
G37*
%LPC*%
G75*
G36*
G01X8441Y129285D02*
X8434D01*
X8356Y129290D01*
X8298Y129293D01*
X8280Y129294D01*
X8161Y129317D01*
X8126Y129324D01*
X8090Y129335D01*
X8026Y129356D01*
X7978Y129371D01*
X7965Y129377D01*
X7893Y129410D01*
X7837Y129436D01*
X7703Y129516D01*
X7654Y129554D01*
X7641Y129563D01*
X7603Y129592D01*
X7578Y129611D01*
X7524Y129661D01*
X7462Y129718D01*
X7413Y129773D01*
X7356Y129838D01*
X7312Y129898D01*
X7268Y129957D01*
X7259Y129969D01*
X7258Y129971D01*
X7219Y130035D01*
X7174Y130109D01*
X7138Y130183D01*
X7101Y130257D01*
X7040Y130412D01*
X7011Y130506D01*
X6991Y130573D01*
X6969Y130681D01*
X6962Y130713D01*
X6957Y130738D01*
X6941Y130863D01*
X6936Y130906D01*
X6930Y131076D01*
X6936Y131173D01*
X6941Y131263D01*
X6957Y131363D01*
X6962Y131397D01*
X6969Y131441D01*
X6991Y131532D01*
X7011Y131611D01*
X7040Y131691D01*
X7068Y131772D01*
X7101Y131843D01*
X7138Y131922D01*
X7174Y131985D01*
X7219Y132063D01*
X7258Y132117D01*
X7259Y132119D01*
X7268Y132131D01*
X7312Y132192D01*
X7356Y132243D01*
X7413Y132310D01*
X7462Y132357D01*
X7524Y132416D01*
X7578Y132459D01*
X7603Y132479D01*
X7641Y132510D01*
X7654Y132518D01*
X7703Y132550D01*
X7765Y132591D01*
X7837Y132628D01*
X7893Y132657D01*
X7965Y132686D01*
X7978Y132691D01*
X8026Y132711D01*
X8090Y132729D01*
X8126Y132739D01*
X8161Y132749D01*
X8280Y132770D01*
X8298Y132773D01*
X8356Y132776D01*
X8434Y132781D01*
X8441D01*
X8457Y132780D01*
X8522Y132776D01*
X8570Y132773D01*
X8590Y132772D01*
X8606Y132769D01*
X8610D01*
X8740Y132746D01*
X8763Y132740D01*
X8828Y132721D01*
X8886Y132704D01*
X8894Y132701D01*
X8913Y132693D01*
X8921Y132689D01*
X8944Y132680D01*
X8953Y132676D01*
X9021Y132648D01*
X9025Y132647D01*
X9056Y132630D01*
X9132Y132589D01*
X9157Y132574D01*
X9189Y132553D01*
X9281Y132489D01*
X9283Y132488D01*
X9313Y132462D01*
X9400Y132388D01*
X9428Y132358D01*
X9431Y132355D01*
X9507Y132275D01*
X9533Y132243D01*
X9592Y132167D01*
X9605Y132150D01*
X9627Y132117D01*
X9692Y132015D01*
X9710Y131981D01*
X9768Y131868D01*
X9782Y131836D01*
X9788Y131819D01*
X9832Y131712D01*
X9841Y131682D01*
X9883Y131547D01*
X9888Y131525D01*
X9889Y131521D01*
X9920Y131374D01*
X9923Y131353D01*
X9943Y131193D01*
X9944Y131176D01*
X9951Y131005D01*
X9944Y130830D01*
X9943Y130824D01*
X9923Y130659D01*
X9920Y130646D01*
X9889Y130495D01*
X9888Y130493D01*
X9883Y130476D01*
X9841Y130337D01*
X9832Y130314D01*
X9788Y130204D01*
X9782Y130187D01*
X9768Y130161D01*
X9710Y130046D01*
X9692Y130017D01*
X9627Y129913D01*
X9605Y129885D01*
X9592Y129868D01*
X9533Y129791D01*
X9507Y129764D01*
X9431Y129683D01*
X9428Y129680D01*
X9400Y129655D01*
X9313Y129581D01*
X9283Y129559D01*
X9281Y129558D01*
X9189Y129494D01*
X9157Y129477D01*
X9132Y129463D01*
X9056Y129421D01*
X9025Y129409D01*
X9021Y129407D01*
X8953Y129380D01*
X8944Y129376D01*
X8921Y129367D01*
X8913Y129363D01*
X8894Y129358D01*
X8886Y129356D01*
X8828Y129339D01*
X8763Y129320D01*
X8740Y129317D01*
X8610Y129295D01*
X8606Y129294D01*
X8590Y129293D01*
X8570Y129292D01*
X8522Y129289D01*
X8457Y129286D01*
X8441Y129285D01*
G37*
G36*
G01X32839Y129426D02*
X32819D01*
X32790Y129427D01*
X32778D01*
X32723Y129432D01*
X32722D01*
X32665Y129437D01*
X32661D01*
X32634Y129442D01*
X32559Y129457D01*
X32553Y129459D01*
X32526Y129468D01*
X32522Y129469D01*
X32479Y129483D01*
X32470Y129487D01*
X32456Y129494D01*
X32420Y129512D01*
X32413Y129515D01*
Y129516D01*
X32405Y129519D01*
X32394Y129525D01*
X32355Y129554D01*
X32343Y129563D01*
X32331Y129571D01*
X32304Y129598D01*
X32279Y129625D01*
X32262Y129650D01*
X32248Y129671D01*
X32239Y129685D01*
X32228Y129708D01*
X32209Y129750D01*
X32203Y129775D01*
X32190Y129821D01*
X32186Y129848D01*
X32180Y129895D01*
X32179Y129973D01*
X32180Y129984D01*
X32186Y130053D01*
X32190Y130072D01*
X32203Y130140D01*
X32209Y130163D01*
X32228Y130226D01*
X32239Y130250D01*
X32248Y130272D01*
X32262Y130305D01*
X32279Y130334D01*
X32304Y130378D01*
X32331Y130412D01*
X32343Y130428D01*
X32355Y130444D01*
X32394Y130483D01*
X32405Y130495D01*
X32413Y130502D01*
Y130503D01*
X32420Y130508D01*
X32456Y130537D01*
X32470Y130548D01*
X32479Y130555D01*
X32522Y130581D01*
X32526Y130583D01*
X32553Y130599D01*
X32559Y130602D01*
X32634Y130637D01*
X32661Y130646D01*
X32665Y130647D01*
X32722Y130666D01*
X32723D01*
X32778Y130679D01*
X32785Y130680D01*
X32790Y130682D01*
X32819Y130688D01*
X32839Y130691D01*
X32889Y130697D01*
X32921Y130702D01*
X32934D01*
X32986Y130705D01*
X33032Y130707D01*
X33058D01*
X33138D01*
X33140D01*
X33172Y130706D01*
X33183D01*
X33185Y130705D01*
X33202D01*
X33234Y130704D01*
X33269Y130702D01*
X33323Y130698D01*
X33346Y130695D01*
X33363Y130693D01*
X33411Y130687D01*
X33478Y130679D01*
X33504Y130674D01*
X33510Y130672D01*
X33535Y130667D01*
X33558Y130661D01*
X33565Y130660D01*
X33579Y130657D01*
X33596Y130653D01*
X33603Y130652D01*
X33610Y130650D01*
X33611D01*
X33615Y130648D01*
X33616D01*
X33627Y130644D01*
X33642Y130639D01*
X33674Y130628D01*
X33697Y130620D01*
X33714Y130614D01*
X33724Y130611D01*
X33751Y130597D01*
X33756Y130595D01*
X33793Y130577D01*
X33804Y130572D01*
X33812Y130567D01*
X33813D01*
X33818Y130565D01*
X33826Y130561D01*
X33835Y130555D01*
X33847Y130548D01*
Y130547D01*
X33872Y130531D01*
X33885Y130523D01*
X33894Y130517D01*
X33896Y130516D01*
X33906Y130509D01*
X33915Y130504D01*
X33920Y130501D01*
X33922Y130500D01*
X33920Y130489D01*
X33915Y130459D01*
X33906Y130413D01*
X33896Y130356D01*
X33894Y130343D01*
X33885Y130288D01*
X33872Y130218D01*
X33847Y130075D01*
Y130074D01*
X33835Y130010D01*
X33826Y129956D01*
Y129954D01*
X33818Y129911D01*
X33813Y129885D01*
Y129879D01*
X33812Y129878D01*
X33804Y129867D01*
X33793Y129855D01*
X33756Y129813D01*
X33751Y129808D01*
X33724Y129783D01*
X33714Y129774D01*
X33697Y129759D01*
X33674Y129738D01*
X33642Y129708D01*
X33627Y129698D01*
X33616Y129691D01*
X33615Y129690D01*
X33611Y129687D01*
X33610D01*
X33603Y129682D01*
X33596Y129677D01*
X33579Y129665D01*
X33565Y129656D01*
X33558Y129651D01*
X33535Y129635D01*
X33510Y129618D01*
X33504Y129614D01*
X33478Y129601D01*
X33411Y129567D01*
X33363Y129543D01*
X33346Y129534D01*
X33323Y129526D01*
X33269Y129507D01*
X33234Y129495D01*
X33202Y129483D01*
X33185Y129478D01*
X33183Y129476D01*
X33172Y129473D01*
X33140Y129467D01*
X33058Y129450D01*
X33055D01*
X33032Y129445D01*
X32986Y129436D01*
X32934Y129432D01*
X32921Y129430D01*
X32889Y129428D01*
X32839Y129426D01*
G37*
G36*
G01X18911D02*
X18890D01*
X18861Y129427D01*
X18850D01*
X18794Y129432D01*
X18736Y129437D01*
X18733D01*
X18706Y129442D01*
X18630Y129457D01*
X18624Y129459D01*
X18597Y129468D01*
X18594Y129469D01*
X18551Y129483D01*
X18541Y129487D01*
X18527Y129494D01*
X18491Y129512D01*
X18485Y129515D01*
X18484Y129516D01*
X18476Y129520D01*
X18465Y129525D01*
X18426Y129554D01*
X18414Y129563D01*
X18402Y129571D01*
X18376Y129598D01*
X18350Y129625D01*
X18334Y129650D01*
X18320Y129670D01*
X18310Y129685D01*
X18300Y129708D01*
X18281Y129750D01*
X18274Y129774D01*
X18261Y129821D01*
X18258Y129846D01*
X18252Y129895D01*
X18250Y129973D01*
X18252Y129983D01*
X18258Y130053D01*
X18261Y130071D01*
X18274Y130140D01*
X18281Y130161D01*
X18300Y130226D01*
X18310Y130250D01*
X18320Y130272D01*
X18334Y130305D01*
X18350Y130334D01*
X18376Y130378D01*
X18402Y130412D01*
X18414Y130428D01*
X18426Y130444D01*
X18465Y130483D01*
X18476Y130494D01*
X18484Y130502D01*
X18485Y130503D01*
X18491Y130508D01*
X18527Y130536D01*
X18541Y130548D01*
X18551Y130555D01*
X18594Y130581D01*
X18597Y130583D01*
X18624Y130599D01*
X18630Y130602D01*
X18706Y130637D01*
X18733Y130646D01*
X18736Y130647D01*
X18794Y130666D01*
X18850Y130679D01*
X18856Y130680D01*
X18861Y130681D01*
X18890Y130688D01*
X18911Y130691D01*
X18960Y130697D01*
X18993Y130702D01*
X19006D01*
X19057Y130705D01*
X19102Y130707D01*
X19130D01*
X19209D01*
X19211D01*
X19244Y130706D01*
X19253D01*
X19256Y130705D01*
X19257D01*
X19272D01*
X19306Y130704D01*
X19339Y130702D01*
X19394Y130698D01*
X19418Y130695D01*
X19435Y130693D01*
X19482Y130687D01*
X19550Y130679D01*
X19575Y130674D01*
X19581Y130672D01*
X19607Y130667D01*
X19629Y130662D01*
X19635Y130660D01*
X19650Y130657D01*
X19667Y130654D01*
X19674Y130652D01*
X19682Y130650D01*
X19686Y130649D01*
X19687Y130648D01*
X19698Y130644D01*
X19713Y130639D01*
X19746Y130628D01*
X19768Y130620D01*
X19785Y130615D01*
X19796Y130611D01*
X19824Y130597D01*
X19828Y130595D01*
X19864Y130577D01*
X19876Y130572D01*
X19884Y130567D01*
X19885D01*
X19890Y130565D01*
X19898Y130561D01*
X19907Y130555D01*
X19918Y130548D01*
X19919Y130547D01*
X19944Y130531D01*
X19956Y130524D01*
X19966Y130517D01*
X19968Y130516D01*
X19978Y130509D01*
X19986Y130504D01*
X19991Y130501D01*
X19993Y130500D01*
X19991Y130489D01*
X19986Y130459D01*
X19978Y130413D01*
X19968Y130356D01*
X19966Y130342D01*
X19956Y130287D01*
X19944Y130218D01*
X19919Y130075D01*
X19918Y130068D01*
X19907Y130010D01*
X19898Y129956D01*
Y129954D01*
X19890Y129911D01*
X19885Y129885D01*
X19884Y129879D01*
Y129878D01*
X19876Y129867D01*
X19864Y129854D01*
X19828Y129813D01*
X19824Y129809D01*
X19796Y129783D01*
X19785Y129774D01*
X19768Y129758D01*
X19746Y129738D01*
X19713Y129708D01*
X19698Y129698D01*
X19687Y129691D01*
Y129690D01*
X19686D01*
X19682Y129687D01*
X19674Y129682D01*
X19667Y129676D01*
X19650Y129665D01*
X19635Y129655D01*
X19629Y129651D01*
X19607Y129635D01*
X19581Y129618D01*
X19575Y129614D01*
X19550Y129601D01*
X19482Y129567D01*
X19435Y129543D01*
X19418Y129534D01*
X19394Y129526D01*
X19339Y129506D01*
X19306Y129494D01*
X19272Y129483D01*
X19257Y129478D01*
X19256D01*
X19253Y129476D01*
X19244Y129473D01*
X19211Y129467D01*
X19209Y129466D01*
X19130Y129450D01*
X19126D01*
X19102Y129445D01*
X19057Y129436D01*
X19006Y129432D01*
X18993Y129430D01*
X18960Y129428D01*
X18911Y129426D01*
G37*
%LPD*%
G75*
G54D10*
G01X-117168Y-317735D02*
Y-322735D01*
G01X-118625Y-317735D02*
X-115711D01*
G01X-110801Y-322735D02*
X-113335D01*
Y-317735D01*
X-110801D01*
G01X-111815Y-320152D02*
X-113335D01*
G01X-108235Y-317735D02*
Y-322735D01*
X-105701D01*
G01X-101868Y-322902D02*
X-101995Y-322818D01*
Y-322652D01*
X-101868Y-322568D01*
X-101741Y-322652D01*
Y-322818D01*
X-101868Y-322902D01*
G01Y-320652D02*
X-101995Y-320568D01*
Y-320402D01*
X-101868Y-320318D01*
X-101741Y-320402D01*
Y-320568D01*
X-101868Y-320652D01*
G01X-97085Y-324402D02*
X-97718Y-323568D01*
X-98035Y-322735D01*
Y-319402D01*
X-97718Y-318568D01*
X-97085Y-317735D01*
G01X-91668D02*
X-92175Y-317902D01*
X-92555Y-318318D01*
X-92808Y-318818D01*
X-92998Y-319485D01*
X-93061Y-320235D01*
X-92998Y-320985D01*
X-92808Y-321652D01*
X-92555Y-322152D01*
X-92175Y-322568D01*
X-91668Y-322735D01*
X-91161Y-322568D01*
X-90781Y-322152D01*
X-90528Y-321652D01*
X-90338Y-320985D01*
X-90275Y-320235D01*
X-90338Y-319485D01*
X-90528Y-318818D01*
X-90781Y-318318D01*
X-91161Y-317902D01*
X-91668Y-317735D01*
G01X-87961Y-321735D02*
X-87581Y-322318D01*
X-87075Y-322652D01*
X-86505Y-322735D01*
X-85998Y-322652D01*
X-85491Y-322235D01*
X-85175Y-321735D01*
X-85111Y-321235D01*
X-85238Y-320652D01*
X-85681Y-320235D01*
X-86125Y-320068D01*
X-86695D01*
G01X-86125D02*
X-85745Y-319818D01*
X-85428Y-319402D01*
X-85301Y-318902D01*
X-85428Y-318402D01*
X-85745Y-317985D01*
X-86315Y-317735D01*
X-86885Y-317818D01*
X-87455Y-318152D01*
G01X-81151Y-324402D02*
X-80518Y-323568D01*
X-80201Y-322735D01*
Y-319402D01*
X-80518Y-318568D01*
X-81151Y-317735D01*
G01X-77761Y-321735D02*
X-77381Y-322318D01*
X-76875Y-322652D01*
X-76305Y-322735D01*
X-75798Y-322652D01*
X-75291Y-322235D01*
X-74975Y-321735D01*
X-74911Y-321235D01*
X-75038Y-320652D01*
X-75481Y-320235D01*
X-75925Y-320068D01*
X-76495D01*
G01X-75925D02*
X-75545Y-319818D01*
X-75228Y-319402D01*
X-75101Y-318902D01*
X-75228Y-318402D01*
X-75545Y-317985D01*
X-76115Y-317735D01*
X-76685Y-317818D01*
X-77255Y-318152D01*
G01X-72471Y-318568D02*
X-72091Y-318068D01*
X-71648Y-317818D01*
X-71141Y-317735D01*
X-70508Y-317902D01*
X-70065Y-318318D01*
X-69938Y-318818D01*
X-70001Y-319318D01*
X-70255Y-319735D01*
X-71521Y-320568D01*
X-72091Y-321152D01*
X-72471Y-321985D01*
X-72598Y-322735D01*
X-69938D01*
G01X-66295D02*
X-66168Y-321652D01*
X-65978Y-320735D01*
X-65725Y-319902D01*
X-65408Y-318985D01*
X-64901Y-317735D01*
X-67435D01*
G01X-61891Y-321068D02*
X-60245D01*
G01X-57171Y-318568D02*
X-56791Y-318068D01*
X-56348Y-317818D01*
X-55841Y-317735D01*
X-55208Y-317902D01*
X-54765Y-318318D01*
X-54638Y-318818D01*
X-54701Y-319318D01*
X-54955Y-319735D01*
X-56221Y-320568D01*
X-56791Y-321152D01*
X-57171Y-321985D01*
X-57298Y-322735D01*
X-54638D01*
G01X-52261Y-321735D02*
X-51881Y-322318D01*
X-51375Y-322652D01*
X-50805Y-322735D01*
X-50298Y-322652D01*
X-49791Y-322235D01*
X-49475Y-321735D01*
X-49411Y-321235D01*
X-49538Y-320652D01*
X-49981Y-320235D01*
X-50425Y-320068D01*
X-50995D01*
G01X-50425D02*
X-50045Y-319818D01*
X-49728Y-319402D01*
X-49601Y-318902D01*
X-49728Y-318402D01*
X-50045Y-317985D01*
X-50615Y-317735D01*
X-51185Y-317818D01*
X-51755Y-318152D01*
G01X-45008Y-322735D02*
Y-317735D01*
X-47351Y-321318D01*
X-44185D01*
G01X-42061Y-321985D02*
X-41681Y-322402D01*
X-41238Y-322652D01*
X-40668Y-322735D01*
X-40098Y-322568D01*
X-39655Y-322235D01*
X-39338Y-321652D01*
X-39275Y-320985D01*
X-39401Y-320318D01*
X-39718Y-319902D01*
X-40161Y-319568D01*
X-40605Y-319485D01*
X-41048Y-319568D01*
X-41618Y-319902D01*
X-41428Y-317735D01*
X-39718D01*
G01X-31671Y-322735D02*
Y-317735D01*
X-29265D01*
G01X-30151Y-320152D02*
X-31671D01*
G01X-26951Y-322735D02*
X-25368Y-317735D01*
X-23785Y-322735D01*
G01X-24355Y-320985D02*
X-26381D01*
G01X-21598Y-322735D02*
X-18938Y-317735D01*
G01X-21598D02*
X-18938Y-322735D01*
G01X-15168Y-322902D02*
X-15295Y-322818D01*
Y-322652D01*
X-15168Y-322568D01*
X-15041Y-322652D01*
Y-322818D01*
X-15168Y-322902D01*
G01Y-320652D02*
X-15295Y-320568D01*
Y-320402D01*
X-15168Y-320318D01*
X-15041Y-320402D01*
Y-320568D01*
X-15168Y-320652D01*
G01X-10385Y-324402D02*
X-11018Y-323568D01*
X-11335Y-322735D01*
Y-319402D01*
X-11018Y-318568D01*
X-10385Y-317735D01*
G01X-4968D02*
X-5475Y-317902D01*
X-5855Y-318318D01*
X-6108Y-318818D01*
X-6298Y-319485D01*
X-6361Y-320235D01*
X-6298Y-320985D01*
X-6108Y-321652D01*
X-5855Y-322152D01*
X-5475Y-322568D01*
X-4968Y-322735D01*
X-4461Y-322568D01*
X-4081Y-322152D01*
X-3828Y-321652D01*
X-3638Y-320985D01*
X-3575Y-320235D01*
X-3638Y-319485D01*
X-3828Y-318818D01*
X-4081Y-318318D01*
X-4461Y-317902D01*
X-4968Y-317735D01*
G01X-1261Y-321735D02*
X-881Y-322318D01*
X-375Y-322652D01*
X195Y-322735D01*
X702Y-322652D01*
X1209Y-322235D01*
X1525Y-321735D01*
X1589Y-321235D01*
X1462Y-320652D01*
X1019Y-320235D01*
X575Y-320068D01*
X5D01*
G01X575D02*
X955Y-319818D01*
X1272Y-319402D01*
X1399Y-318902D01*
X1272Y-318402D01*
X955Y-317985D01*
X385Y-317735D01*
X-185Y-317818D01*
X-755Y-318152D01*
G01X5549Y-324402D02*
X6182Y-323568D01*
X6499Y-322735D01*
Y-319402D01*
X6182Y-318568D01*
X5549Y-317735D01*
G01X8939Y-321735D02*
X9319Y-322318D01*
X9825Y-322652D01*
X10395Y-322735D01*
X10902Y-322652D01*
X11409Y-322235D01*
X11725Y-321735D01*
X11789Y-321235D01*
X11662Y-320652D01*
X11219Y-320235D01*
X10775Y-320068D01*
X10205D01*
G01X10775D02*
X11155Y-319818D01*
X11472Y-319402D01*
X11599Y-318902D01*
X11472Y-318402D01*
X11155Y-317985D01*
X10585Y-317735D01*
X10015Y-317818D01*
X9445Y-318152D01*
G01X14355Y-322152D02*
X14799Y-322568D01*
X15305Y-322735D01*
X15812Y-322568D01*
X16255Y-322068D01*
X16572Y-321318D01*
X16699Y-320568D01*
Y-319652D01*
X16572Y-318902D01*
X16255Y-318235D01*
X15875Y-317902D01*
X15432Y-317735D01*
X14925Y-317902D01*
X14545Y-318235D01*
X14292Y-318735D01*
X14165Y-319402D01*
X14292Y-319985D01*
X14609Y-320568D01*
X14989Y-320902D01*
X15432Y-320985D01*
X15939Y-320818D01*
X16319Y-320402D01*
X16699Y-319652D01*
G01X20405Y-322735D02*
X20532Y-321652D01*
X20722Y-320735D01*
X20975Y-319902D01*
X21292Y-318985D01*
X21799Y-317735D01*
X19265D01*
G01X24809Y-321068D02*
X26455D01*
G01X29339Y-321735D02*
X29719Y-322318D01*
X30225Y-322652D01*
X30795Y-322735D01*
X31302Y-322652D01*
X31809Y-322235D01*
X32125Y-321735D01*
X32189Y-321235D01*
X32062Y-320652D01*
X31619Y-320235D01*
X31175Y-320068D01*
X30605D01*
G01X31175D02*
X31555Y-319818D01*
X31872Y-319402D01*
X31999Y-318902D01*
X31872Y-318402D01*
X31555Y-317985D01*
X30985Y-317735D01*
X30415Y-317818D01*
X29845Y-318152D01*
G01X34629Y-320652D02*
X35072Y-320068D01*
X35452Y-319735D01*
X35959Y-319568D01*
X36402Y-319735D01*
X36719Y-320068D01*
X36972Y-320568D01*
X37035Y-321152D01*
X36972Y-321652D01*
X36719Y-322152D01*
X36339Y-322568D01*
X35895Y-322735D01*
X35389Y-322568D01*
X34945Y-322068D01*
X34692Y-321318D01*
X34629Y-320485D01*
X34755Y-319402D01*
X34945Y-318818D01*
X35262Y-318235D01*
X35705Y-317818D01*
X36149Y-317735D01*
X36592Y-317902D01*
X36909Y-318318D01*
G01X40932Y-322735D02*
Y-317735D01*
X40172Y-318735D01*
G01Y-322735D02*
X41692D01*
G01X46792D02*
Y-317735D01*
X44449Y-321318D01*
X47615D01*
G01X-129168Y-252735D02*
Y-327735D01*
X370832D01*
Y-252735D01*
X-129168D01*
G01X150394Y283264D02*
Y307087D01*
G03X142520Y314961I-7874J0D01*
G01X129331D01*
G02X121457Y322835I0J7874D01*
G01Y331299D01*
G03X113583Y339173I-7874J0D01*
G01X58465D01*
G03X50591Y331299I0J-7874D01*
G01Y322835D01*
G02X42717Y314961I-7874J0D01*
G01X12205D01*
G03X4331Y307087I0J-7874D01*
G01Y283264D01*
G02X2165Y277840I-7875J0D01*
G03X0Y272417I5709J-5423D01*
G01Y7874D01*
G03X7874Y0I7874J0D01*
G01X146850D01*
G03X154724Y7874I0J7874D01*
G01Y272417D01*
G03X152559Y277840I-7874J0D01*
G02X150394Y283264I5710J5423D01*
G01X24016Y50787D02*
G02Y66535I0J7874D01*
G02Y50787I0J-7874D01*
G01X33640Y287042D02*
G03X31890Y282093I6124J-4949D01*
G01Y279449D01*
G02X20079I-5905J0D01*
G01Y282093D01*
G03X18329Y287042I-7874J0D01*
G02X33640I7656J6187D01*
G01X65832Y-252735D02*
Y-327735D01*
G01Y-302735D02*
X168832D01*
Y-277735D01*
G01X65832D02*
X168832D01*
G01X129134Y239669D02*
G02Y255417I0J7874D01*
G02Y239669I0J-7874D01*
G01X143876Y51018D02*
G03X142126Y46069I6124J-4949D01*
G01Y43425D01*
G02X130315I-5906J0D01*
G01Y46069D01*
G03X128565Y51018I-7874J0D01*
G02X143876I7655J6187D01*
G01X176339Y-312735D02*
Y-307735D01*
X177605D01*
X178112Y-307985D01*
X178492Y-308318D01*
X178809Y-308818D01*
X179062Y-309402D01*
X179125Y-310235D01*
X179062Y-311068D01*
X178809Y-311652D01*
X178492Y-312152D01*
X178112Y-312485D01*
X177605Y-312735D01*
X176339D01*
G01X181249D02*
X182832Y-307735D01*
X184415Y-312735D01*
G01X183845Y-310985D02*
X181819D01*
G01X187932Y-307735D02*
Y-312735D01*
G01X186475Y-307735D02*
X189389D01*
G01X194299Y-312735D02*
X191765D01*
Y-307735D01*
X194299D01*
G01X193285Y-310152D02*
X191765D01*
G01X198132Y-312902D02*
X198005Y-312818D01*
Y-312652D01*
X198132Y-312568D01*
X198259Y-312652D01*
Y-312818D01*
X198132Y-312902D01*
G01Y-310652D02*
X198005Y-310568D01*
Y-310402D01*
X198132Y-310318D01*
X198259Y-310402D01*
Y-310568D01*
X198132Y-310652D01*
G01X170832Y-252735D02*
Y-327735D01*
G01X168832Y-252735D02*
Y-327735D01*
G01X170832Y-302735D02*
X370832D01*
G01X176465Y-287735D02*
Y-282735D01*
X177985D01*
X178492Y-282985D01*
X178872Y-283568D01*
X178999Y-284235D01*
X178872Y-284902D01*
X178555Y-285402D01*
X177985Y-285652D01*
X176465D01*
G01X181692Y-287902D02*
X183972Y-282735D01*
G01X186475Y-287735D02*
Y-282735D01*
X189389Y-287735D01*
Y-282735D01*
G01X193032Y-287902D02*
X192905Y-287818D01*
Y-287652D01*
X193032Y-287568D01*
X193159Y-287652D01*
Y-287818D01*
X193032Y-287902D01*
G01Y-285652D02*
X192905Y-285568D01*
Y-285402D01*
X193032Y-285318D01*
X193159Y-285402D01*
Y-285568D01*
X193032Y-285652D01*
G01X170832Y-277735D02*
X370832D01*
G01X176465Y-262735D02*
Y-257735D01*
X177985D01*
X178492Y-257985D01*
X178872Y-258568D01*
X178999Y-259235D01*
X178872Y-259902D01*
X178555Y-260402D01*
X177985Y-260652D01*
X176465D01*
G01X181565Y-262735D02*
Y-257735D01*
X183149D01*
X183655Y-257985D01*
X183972Y-258318D01*
X184099Y-258985D01*
X183972Y-259652D01*
X183592Y-260068D01*
X183149Y-260318D01*
X181565D01*
G01X183149D02*
X184099Y-262735D01*
G01X187932D02*
X187425Y-262652D01*
X186982Y-262318D01*
X186602Y-261818D01*
X186349Y-261235D01*
X186222Y-260568D01*
Y-259902D01*
X186349Y-259235D01*
X186602Y-258652D01*
X186982Y-258152D01*
X187425Y-257818D01*
X187932Y-257735D01*
X188439Y-257818D01*
X188882Y-258152D01*
X189262Y-258652D01*
X189515Y-259235D01*
X189642Y-259902D01*
Y-260568D01*
X189515Y-261235D01*
X189262Y-261818D01*
X188882Y-262318D01*
X188439Y-262652D01*
X187932Y-262735D01*
G01X191765Y-261735D02*
X192082Y-262235D01*
X192462Y-262568D01*
X192905Y-262735D01*
X193412Y-262568D01*
X193792Y-262235D01*
X194172Y-261735D01*
X194299Y-261068D01*
Y-257735D01*
G01X199399Y-262735D02*
X196865D01*
Y-257735D01*
X199399D01*
G01X198385Y-260152D02*
X196865D01*
G01X204625Y-258152D02*
X204245Y-257902D01*
X203802Y-257735D01*
X203295D01*
X202725Y-257985D01*
X202282Y-258402D01*
X201965Y-258902D01*
X201712Y-259735D01*
X201649Y-260485D01*
X201775Y-261235D01*
X201965Y-261735D01*
X202345Y-262235D01*
X202789Y-262568D01*
X203232Y-262735D01*
X203675D01*
X204119Y-262568D01*
X204499Y-262318D01*
X204815Y-261985D01*
G01X208332Y-257735D02*
Y-262735D01*
G01X206875Y-257735D02*
X209789D01*
G01X213432Y-262902D02*
X213305Y-262818D01*
Y-262652D01*
X213432Y-262568D01*
X213559Y-262652D01*
Y-262818D01*
X213432Y-262902D01*
G01Y-260652D02*
X213305Y-260568D01*
Y-260402D01*
X213432Y-260318D01*
X213559Y-260402D01*
Y-260568D01*
X213432Y-260652D01*
G01X283832Y-302735D02*
Y-327735D01*
G01X288465Y-305235D02*
Y-310235D01*
X290999D01*
G01X294072Y-305235D02*
X295592D01*
G01X294832D02*
Y-310235D01*
G01X294072D02*
X295592D01*
G01X300439Y-307568D02*
X300692Y-307318D01*
X300882Y-306902D01*
X301009Y-306318D01*
X300882Y-305818D01*
X300629Y-305485D01*
X300185Y-305235D01*
X298475D01*
Y-310235D01*
X300565D01*
X301009Y-309902D01*
X301262Y-309402D01*
X301389Y-308818D01*
X301262Y-308235D01*
X300882Y-307735D01*
X300439Y-307568D01*
X298475D01*
G01X305032Y-310402D02*
X304905Y-310318D01*
Y-310152D01*
X305032Y-310068D01*
X305159Y-310152D01*
Y-310318D01*
X305032Y-310402D01*
G01Y-308152D02*
X304905Y-308068D01*
Y-307902D01*
X305032Y-307818D01*
X305159Y-307902D01*
Y-308068D01*
X305032Y-308152D01*
G01X328832Y-302735D02*
Y-327735D01*
G01X332732Y-305235D02*
Y-310235D01*
G01X331275Y-305235D02*
X334189D01*
G01X337832Y-310235D02*
X337452Y-310152D01*
X337072Y-309818D01*
X336819Y-309235D01*
X336692Y-308568D01*
X336819Y-307902D01*
X337072Y-307318D01*
X337452Y-306985D01*
X337832Y-306902D01*
X338212Y-306985D01*
X338592Y-307318D01*
X338845Y-307902D01*
X338909Y-308568D01*
X338845Y-309235D01*
X338592Y-309818D01*
X338212Y-310152D01*
X337832Y-310235D01*
G01X342932D02*
X342552Y-310152D01*
X342172Y-309818D01*
X341919Y-309235D01*
X341792Y-308568D01*
X341919Y-307902D01*
X342172Y-307318D01*
X342552Y-306985D01*
X342932Y-306902D01*
X343312Y-306985D01*
X343692Y-307318D01*
X343945Y-307902D01*
X344009Y-308568D01*
X343945Y-309235D01*
X343692Y-309818D01*
X343312Y-310152D01*
X342932Y-310235D01*
G01X348032D02*
Y-305235D01*
G01X353132Y-310402D02*
X353005Y-310318D01*
Y-310152D01*
X353132Y-310068D01*
X353259Y-310152D01*
Y-310318D01*
X353132Y-310402D01*
G01Y-308152D02*
X353005Y-308068D01*
Y-307902D01*
X353132Y-307818D01*
X353259Y-307902D01*
Y-308068D01*
X353132Y-308152D01*
G01X328832Y-277735D02*
Y-302735D01*
G01X331465Y-285235D02*
Y-280235D01*
X333049D01*
X333555Y-280485D01*
X333872Y-280818D01*
X333999Y-281485D01*
X333872Y-282152D01*
X333492Y-282568D01*
X333049Y-282818D01*
X331465D01*
G01X333049D02*
X333999Y-285235D01*
G01X339099D02*
X336565D01*
Y-280235D01*
X339099D01*
G01X338085Y-282652D02*
X336565D01*
G01X341349Y-280235D02*
X342932Y-285235D01*
X344515Y-280235D01*
G01X348032Y-285402D02*
X347905Y-285318D01*
Y-285152D01*
X348032Y-285068D01*
X348159Y-285152D01*
Y-285318D01*
X348032Y-285402D01*
G01Y-283152D02*
X347905Y-283068D01*
Y-282902D01*
X348032Y-282818D01*
X348159Y-282902D01*
Y-283068D01*
X348032Y-283152D01*
G01X351592Y-329435D02*
X351672Y-329360D01*
X351732Y-329235D01*
X351772Y-329060D01*
X351732Y-328910D01*
X351652Y-328810D01*
X351512Y-328735D01*
X350972D01*
Y-330235D01*
X351632D01*
X351772Y-330135D01*
X351852Y-329985D01*
X351892Y-329810D01*
X351852Y-329635D01*
X351732Y-329485D01*
X351592Y-329435D01*
X350972D01*
G01X352992Y-330235D02*
Y-329235D01*
G01Y-329410D02*
X352912Y-329310D01*
X352792Y-329260D01*
X352652Y-329235D01*
X352512Y-329285D01*
X352392Y-329385D01*
X352312Y-329535D01*
X352272Y-329735D01*
X352312Y-329935D01*
X352392Y-330085D01*
X352512Y-330185D01*
X352652Y-330235D01*
X352792Y-330210D01*
X352912Y-330135D01*
X352992Y-330035D01*
G01X353532Y-330060D02*
X353632Y-330160D01*
X353772Y-330235D01*
X353892D01*
X354012Y-330185D01*
X354092Y-330110D01*
X354132Y-330010D01*
X354112Y-329860D01*
X354032Y-329785D01*
X353672Y-329635D01*
X353592Y-329460D01*
X353632Y-329335D01*
X353712Y-329260D01*
X353832Y-329235D01*
X353952Y-329260D01*
X354072Y-329335D01*
G01X354732Y-329560D02*
X355372D01*
X355312Y-329385D01*
X355212Y-329285D01*
X355072Y-329235D01*
X354932Y-329260D01*
X354812Y-329335D01*
X354732Y-329510D01*
X354692Y-329660D01*
Y-329810D01*
X354732Y-329960D01*
X354832Y-330110D01*
X354952Y-330210D01*
X355092Y-330235D01*
X355232Y-330185D01*
X355372Y-330035D01*
G01X355872Y-330235D02*
Y-328735D01*
G01Y-329485D02*
X355972Y-329335D01*
X356092Y-329260D01*
X356212Y-329235D01*
X356392Y-329285D01*
X356512Y-329385D01*
X356592Y-329560D01*
Y-329760D01*
X356552Y-329960D01*
X356472Y-330110D01*
X356332Y-330210D01*
X356212Y-330235D01*
X356092Y-330210D01*
X355972Y-330135D01*
X355872Y-330010D01*
G01X357432Y-330235D02*
X357312Y-330210D01*
X357192Y-330110D01*
X357112Y-329935D01*
X357072Y-329735D01*
X357112Y-329535D01*
X357192Y-329360D01*
X357312Y-329260D01*
X357432Y-329235D01*
X357552Y-329260D01*
X357672Y-329360D01*
X357752Y-329535D01*
X357772Y-329735D01*
X357752Y-329935D01*
X357672Y-330110D01*
X357552Y-330210D01*
X357432Y-330235D01*
G01X358992D02*
Y-329235D01*
G01Y-329410D02*
X358912Y-329310D01*
X358792Y-329260D01*
X358652Y-329235D01*
X358512Y-329285D01*
X358392Y-329385D01*
X358312Y-329535D01*
X358272Y-329735D01*
X358312Y-329935D01*
X358392Y-330085D01*
X358512Y-330185D01*
X358652Y-330235D01*
X358792Y-330210D01*
X358912Y-330135D01*
X358992Y-330035D01*
G01X359552Y-330235D02*
Y-329235D01*
G01Y-329435D02*
X359652Y-329335D01*
X359752Y-329260D01*
X359892Y-329235D01*
X359992Y-329260D01*
X360112Y-329335D01*
G01X361392Y-328735D02*
Y-330235D01*
G01Y-330010D02*
X361312Y-330135D01*
X361192Y-330210D01*
X361052Y-330235D01*
X360892Y-330185D01*
X360772Y-330060D01*
X360692Y-329910D01*
X360672Y-329735D01*
X360692Y-329560D01*
X360772Y-329410D01*
X360892Y-329285D01*
X361052Y-329235D01*
X361192Y-329260D01*
X361292Y-329310D01*
X361392Y-329410D01*
G01X363032Y-330235D02*
Y-328735D01*
X363532D01*
X363692Y-328810D01*
X363792Y-328910D01*
X363832Y-329110D01*
X363792Y-329310D01*
X363672Y-329435D01*
X363532Y-329510D01*
X363032D01*
G01X363532D02*
X363832Y-330235D01*
G01X364332Y-329560D02*
X364972D01*
X364912Y-329385D01*
X364812Y-329285D01*
X364672Y-329235D01*
X364532Y-329260D01*
X364412Y-329335D01*
X364332Y-329510D01*
X364292Y-329660D01*
Y-329810D01*
X364332Y-329960D01*
X364432Y-330110D01*
X364552Y-330210D01*
X364692Y-330235D01*
X364832Y-330185D01*
X364972Y-330035D01*
G01X365472Y-329235D02*
X365832Y-330235D01*
X366192Y-329235D01*
G01X367032Y-330285D02*
X366992Y-330260D01*
Y-330210D01*
X367032Y-330185D01*
X367072Y-330210D01*
Y-330260D01*
X367032Y-330285D01*
G01X368192Y-330235D02*
X368232Y-329910D01*
X368292Y-329635D01*
X368372Y-329385D01*
X368472Y-329110D01*
X368632Y-328735D01*
X367832D01*
G01X369592Y-329435D02*
X369672Y-329360D01*
X369732Y-329235D01*
X369772Y-329060D01*
X369732Y-328910D01*
X369652Y-328810D01*
X369512Y-328735D01*
X368972D01*
Y-330235D01*
X369632D01*
X369772Y-330135D01*
X369852Y-329985D01*
X369892Y-329810D01*
X369852Y-329635D01*
X369732Y-329485D01*
X369592Y-329435D01*
X368972D01*
G01X-247901Y-428634D02*
Y1008173D01*
X2091018D01*
Y-428634D01*
X-247901D01*
G01X-115095Y-307460D02*
X-115565Y-307145D01*
X-116113Y-306935D01*
X-116740D01*
X-117445Y-307250D01*
X-117993Y-307775D01*
X-118385Y-308405D01*
X-118698Y-309455D01*
X-118776Y-310400D01*
X-118620Y-311345D01*
X-118385Y-311975D01*
X-117915Y-312605D01*
X-117366Y-313025D01*
X-116818Y-313235D01*
X-116270D01*
X-115721Y-313025D01*
X-115251Y-312710D01*
X-114860Y-312290D01*
G01X-111458Y-306935D02*
X-109578D01*
G01X-110518D02*
Y-313235D01*
G01X-111458D02*
X-109578D01*
G01X-104218Y-306935D02*
Y-313235D01*
G01X-106020Y-306935D02*
X-102416D01*
G01X-97918Y-313235D02*
Y-310400D01*
X-99485Y-306935D01*
G01X-96351D02*
X-97918Y-310400D01*
G01X-87041Y-311975D02*
X-86571Y-312710D01*
X-85945Y-313130D01*
X-85240Y-313235D01*
X-84613Y-313130D01*
X-83986Y-312605D01*
X-83595Y-311975D01*
X-83516Y-311345D01*
X-83673Y-310610D01*
X-84221Y-310085D01*
X-84770Y-309875D01*
X-85475D01*
G01X-84770D02*
X-84300Y-309560D01*
X-83908Y-309035D01*
X-83751Y-308405D01*
X-83908Y-307775D01*
X-84300Y-307250D01*
X-85005Y-306935D01*
X-85710Y-307040D01*
X-86415Y-307460D01*
G01X-80741Y-311975D02*
X-80271Y-312710D01*
X-79645Y-313130D01*
X-78940Y-313235D01*
X-78313Y-313130D01*
X-77686Y-312605D01*
X-77295Y-311975D01*
X-77216Y-311345D01*
X-77373Y-310610D01*
X-77921Y-310085D01*
X-78470Y-309875D01*
X-79175D01*
G01X-78470D02*
X-78000Y-309560D01*
X-77608Y-309035D01*
X-77451Y-308405D01*
X-77608Y-307775D01*
X-78000Y-307250D01*
X-78705Y-306935D01*
X-79410Y-307040D01*
X-80115Y-307460D01*
G01X-74441Y-311975D02*
X-73971Y-312710D01*
X-73345Y-313130D01*
X-72640Y-313235D01*
X-72013Y-313130D01*
X-71386Y-312605D01*
X-70995Y-311975D01*
X-70916Y-311345D01*
X-71073Y-310610D01*
X-71621Y-310085D01*
X-72170Y-309875D01*
X-72875D01*
G01X-72170D02*
X-71700Y-309560D01*
X-71308Y-309035D01*
X-71151Y-308405D01*
X-71308Y-307775D01*
X-71700Y-307250D01*
X-72405Y-306935D01*
X-73110Y-307040D01*
X-73815Y-307460D01*
G01X-66575Y-313235D02*
X-66418Y-311870D01*
X-66183Y-310715D01*
X-65870Y-309665D01*
X-65478Y-308510D01*
X-64851Y-306935D01*
X-67985D01*
G01X-60275Y-313235D02*
X-60118Y-311870D01*
X-59883Y-310715D01*
X-59570Y-309665D01*
X-59178Y-308510D01*
X-58551Y-306935D01*
X-61685D01*
G01X-53975Y-314390D02*
X-53661Y-313025D01*
G01X-47518Y-306935D02*
Y-313235D01*
G01X-49320Y-306935D02*
X-45716D01*
G01X-43176Y-313235D02*
X-41218Y-306935D01*
X-39260Y-313235D01*
G01X-39965Y-311030D02*
X-42471D01*
G01X-35858Y-306935D02*
X-33978D01*
G01X-34918D02*
Y-313235D01*
G01X-35858D02*
X-33978D01*
G01X-30968Y-306935D02*
X-29871Y-313235D01*
X-28618Y-306935D01*
X-27365Y-313235D01*
X-26268Y-306935D01*
G01X-24276Y-313235D02*
X-22318Y-306935D01*
X-20360Y-313235D01*
G01X-21065Y-311030D02*
X-23571D01*
G01X-17820Y-313235D02*
Y-306935D01*
X-14216Y-313235D01*
Y-306935D01*
G01X-3810Y-315335D02*
X-4593Y-314285D01*
X-4985Y-313235D01*
Y-309035D01*
X-4593Y-307985D01*
X-3810Y-306935D01*
G01X7615Y-313235D02*
Y-306935D01*
X9574D01*
X10200Y-307250D01*
X10592Y-307670D01*
X10749Y-308510D01*
X10592Y-309350D01*
X10122Y-309875D01*
X9574Y-310190D01*
X7615D01*
G01X9574D02*
X10749Y-313235D01*
G01X15482Y-313445D02*
X15325Y-313340D01*
Y-313130D01*
X15482Y-313025D01*
X15639Y-313130D01*
Y-313340D01*
X15482Y-313445D01*
G01X21782Y-313235D02*
X21155Y-313130D01*
X20607Y-312710D01*
X20137Y-312080D01*
X19824Y-311345D01*
X19667Y-310505D01*
Y-309665D01*
X19824Y-308825D01*
X20137Y-308090D01*
X20607Y-307460D01*
X21155Y-307040D01*
X21782Y-306935D01*
X22409Y-307040D01*
X22957Y-307460D01*
X23427Y-308090D01*
X23740Y-308825D01*
X23897Y-309665D01*
Y-310505D01*
X23740Y-311345D01*
X23427Y-312080D01*
X22957Y-312710D01*
X22409Y-313130D01*
X21782Y-313235D01*
G01X28082Y-313445D02*
X27925Y-313340D01*
Y-313130D01*
X28082Y-313025D01*
X28239Y-313130D01*
Y-313340D01*
X28082Y-313445D01*
G01X36105Y-307460D02*
X35635Y-307145D01*
X35087Y-306935D01*
X34460D01*
X33755Y-307250D01*
X33207Y-307775D01*
X32815Y-308405D01*
X32502Y-309455D01*
X32424Y-310400D01*
X32580Y-311345D01*
X32815Y-311975D01*
X33285Y-312605D01*
X33834Y-313025D01*
X34382Y-313235D01*
X34930D01*
X35479Y-313025D01*
X35949Y-312710D01*
X36340Y-312290D01*
G01X40682Y-313445D02*
X40525Y-313340D01*
Y-313130D01*
X40682Y-313025D01*
X40839Y-313130D01*
Y-313340D01*
X40682Y-313445D01*
G01X47374Y-315335D02*
X48157Y-314285D01*
X48549Y-313235D01*
Y-309035D01*
X48157Y-307985D01*
X47374Y-306935D01*
G01X-118620Y-293235D02*
Y-286935D01*
X-115016Y-293235D01*
Y-286935D01*
G01X-110518Y-293235D02*
X-111145Y-293130D01*
X-111693Y-292710D01*
X-112163Y-292080D01*
X-112476Y-291345D01*
X-112633Y-290505D01*
Y-289665D01*
X-112476Y-288825D01*
X-112163Y-288090D01*
X-111693Y-287460D01*
X-111145Y-287040D01*
X-110518Y-286935D01*
X-109891Y-287040D01*
X-109343Y-287460D01*
X-108873Y-288090D01*
X-108560Y-288825D01*
X-108403Y-289665D01*
Y-290505D01*
X-108560Y-291345D01*
X-108873Y-292080D01*
X-109343Y-292710D01*
X-109891Y-293130D01*
X-110518Y-293235D01*
G01X-104218Y-293445D02*
X-104375Y-293340D01*
Y-293130D01*
X-104218Y-293025D01*
X-104061Y-293130D01*
Y-293340D01*
X-104218Y-293445D01*
G01X-99406Y-287985D02*
X-98936Y-287355D01*
X-98388Y-287040D01*
X-97761Y-286935D01*
X-96978Y-287145D01*
X-96430Y-287670D01*
X-96273Y-288300D01*
X-96351Y-288930D01*
X-96665Y-289455D01*
X-98231Y-290505D01*
X-98936Y-291240D01*
X-99406Y-292290D01*
X-99563Y-293235D01*
X-96273D01*
G01X-91618D02*
Y-286935D01*
X-92558Y-288195D01*
G01Y-293235D02*
X-90678D01*
G01X-85318D02*
Y-286935D01*
X-86258Y-288195D01*
G01Y-293235D02*
X-84378D01*
G01X-79175Y-294390D02*
X-78861Y-293025D01*
G01X-75068Y-286935D02*
X-73971Y-293235D01*
X-72718Y-286935D01*
X-71465Y-293235D01*
X-70368Y-286935D01*
G01X-64851Y-293235D02*
X-67985D01*
Y-286935D01*
X-64851D01*
G01X-66105Y-289980D02*
X-67985D01*
G01X-61920Y-293235D02*
Y-286935D01*
X-58316Y-293235D01*
Y-286935D01*
G01X-55463Y-293235D02*
Y-286935D01*
G01X-52173D02*
Y-293235D01*
G01Y-290085D02*
X-55463D01*
G01X-49241Y-286935D02*
Y-291450D01*
X-48928Y-292395D01*
X-48301Y-293025D01*
X-47518Y-293235D01*
X-46735Y-293025D01*
X-46108Y-292395D01*
X-45795Y-291450D01*
Y-286935D01*
G01X-43176Y-293235D02*
X-41218Y-286935D01*
X-39260Y-293235D01*
G01X-39965Y-291030D02*
X-42471D01*
G01X-30106Y-287985D02*
X-29636Y-287355D01*
X-29088Y-287040D01*
X-28461Y-286935D01*
X-27678Y-287145D01*
X-27130Y-287670D01*
X-26973Y-288300D01*
X-27051Y-288930D01*
X-27365Y-289455D01*
X-28931Y-290505D01*
X-29636Y-291240D01*
X-30106Y-292290D01*
X-30263Y-293235D01*
X-26973D01*
G01X-24120D02*
Y-286935D01*
X-20516Y-293235D01*
Y-286935D01*
G01X-17741Y-293235D02*
Y-286935D01*
X-16175D01*
X-15548Y-287250D01*
X-15078Y-287670D01*
X-14686Y-288300D01*
X-14373Y-289035D01*
X-14295Y-290085D01*
X-14373Y-291135D01*
X-14686Y-291870D01*
X-15078Y-292500D01*
X-15548Y-292920D01*
X-16175Y-293235D01*
X-17741D01*
G01X-4985D02*
Y-286935D01*
X-3026D01*
X-2400Y-287250D01*
X-2008Y-287670D01*
X-1851Y-288510D01*
X-2008Y-289350D01*
X-2478Y-289875D01*
X-3026Y-290190D01*
X-4985D01*
G01X-3026D02*
X-1851Y-293235D01*
G01X1159D02*
Y-286935D01*
X2725D01*
X3352Y-287250D01*
X3822Y-287670D01*
X4214Y-288300D01*
X4527Y-289035D01*
X4605Y-290085D01*
X4527Y-291135D01*
X4214Y-291870D01*
X3822Y-292500D01*
X3352Y-292920D01*
X2725Y-293235D01*
X1159D01*
G01X9182Y-293445D02*
X9025Y-293340D01*
Y-293130D01*
X9182Y-293025D01*
X9339Y-293130D01*
Y-293340D01*
X9182Y-293445D01*
G01X-116348Y-300085D02*
X-114781D01*
Y-301975D01*
X-115251Y-302605D01*
X-115800Y-303025D01*
X-116583Y-303235D01*
X-117366Y-303025D01*
X-117915Y-302605D01*
X-118385Y-301975D01*
X-118698Y-301240D01*
X-118855Y-300400D01*
Y-299665D01*
X-118698Y-299035D01*
X-118385Y-298300D01*
X-117915Y-297670D01*
X-117445Y-297250D01*
X-116818Y-296935D01*
X-116270D01*
X-115643Y-297145D01*
X-115173Y-297565D01*
G01X-112241Y-296935D02*
Y-301450D01*
X-111928Y-302395D01*
X-111301Y-303025D01*
X-110518Y-303235D01*
X-109735Y-303025D01*
X-109108Y-302395D01*
X-108795Y-301450D01*
Y-296935D01*
G01X-105158D02*
X-103278D01*
G01X-104218D02*
Y-303235D01*
G01X-105158D02*
X-103278D01*
G01X-99563Y-302395D02*
X-98936Y-302920D01*
X-98231Y-303235D01*
X-97605D01*
X-96978Y-302920D01*
X-96508Y-302395D01*
X-96273Y-301660D01*
X-96430Y-300925D01*
X-96821Y-300295D01*
X-97526Y-299875D01*
X-98466Y-299665D01*
X-99015Y-299245D01*
X-99250Y-298510D01*
X-99093Y-297775D01*
X-98701Y-297250D01*
X-98153Y-296935D01*
X-97605D01*
X-97056Y-297145D01*
X-96586Y-297670D01*
G01X-93263Y-303235D02*
Y-296935D01*
G01X-89973D02*
Y-303235D01*
G01Y-300085D02*
X-93263D01*
G01X-87276Y-303235D02*
X-85318Y-296935D01*
X-83360Y-303235D01*
G01X-84065Y-301030D02*
X-86571D01*
G01X-80820Y-303235D02*
Y-296935D01*
X-77216Y-303235D01*
Y-296935D01*
G01X-68141Y-303235D02*
Y-296935D01*
X-66575D01*
X-65948Y-297250D01*
X-65478Y-297670D01*
X-65086Y-298300D01*
X-64773Y-299035D01*
X-64695Y-300085D01*
X-64773Y-301135D01*
X-65086Y-301870D01*
X-65478Y-302500D01*
X-65948Y-302920D01*
X-66575Y-303235D01*
X-68141D01*
G01X-61058Y-296935D02*
X-59178D01*
G01X-60118D02*
Y-303235D01*
G01X-61058D02*
X-59178D01*
G01X-55463Y-302395D02*
X-54836Y-302920D01*
X-54131Y-303235D01*
X-53505D01*
X-52878Y-302920D01*
X-52408Y-302395D01*
X-52173Y-301660D01*
X-52330Y-300925D01*
X-52721Y-300295D01*
X-53426Y-299875D01*
X-54366Y-299665D01*
X-54915Y-299245D01*
X-55150Y-298510D01*
X-54993Y-297775D01*
X-54601Y-297250D01*
X-54053Y-296935D01*
X-53505D01*
X-52956Y-297145D01*
X-52486Y-297670D01*
G01X-47518Y-296935D02*
Y-303235D01*
G01X-49320Y-296935D02*
X-45716D01*
G01X-41218Y-303445D02*
X-41375Y-303340D01*
Y-303130D01*
X-41218Y-303025D01*
X-41061Y-303130D01*
Y-303340D01*
X-41218Y-303445D01*
G01X-35075Y-304390D02*
X-34761Y-303025D01*
G01X-28618Y-296935D02*
Y-303235D01*
G01X-30420Y-296935D02*
X-26816D01*
G01X-24276Y-303235D02*
X-22318Y-296935D01*
X-20360Y-303235D01*
G01X-21065Y-301030D02*
X-23571D01*
G01X-16018Y-303235D02*
X-16645Y-303130D01*
X-17193Y-302710D01*
X-17663Y-302080D01*
X-17976Y-301345D01*
X-18133Y-300505D01*
Y-299665D01*
X-17976Y-298825D01*
X-17663Y-298090D01*
X-17193Y-297460D01*
X-16645Y-297040D01*
X-16018Y-296935D01*
X-15391Y-297040D01*
X-14843Y-297460D01*
X-14373Y-298090D01*
X-14060Y-298825D01*
X-13903Y-299665D01*
Y-300505D01*
X-14060Y-301345D01*
X-14373Y-302080D01*
X-14843Y-302710D01*
X-15391Y-303130D01*
X-16018Y-303235D01*
G01X-9718D02*
Y-300400D01*
X-11285Y-296935D01*
G01X-8151D02*
X-9718Y-300400D01*
G01X-5141Y-296935D02*
Y-301450D01*
X-4828Y-302395D01*
X-4201Y-303025D01*
X-3418Y-303235D01*
X-2635Y-303025D01*
X-2008Y-302395D01*
X-1695Y-301450D01*
Y-296935D01*
G01X924Y-303235D02*
X2882Y-296935D01*
X4840Y-303235D01*
G01X4135Y-301030D02*
X1629D01*
G01X7380Y-303235D02*
Y-296935D01*
X10984Y-303235D01*
Y-296935D01*
G01X-94518Y-282535D02*
X-97038Y-282118D01*
X-99243Y-280452D01*
X-101133Y-277952D01*
X-102393Y-275035D01*
X-103023Y-271702D01*
Y-268368D01*
X-102393Y-265035D01*
X-101133Y-262118D01*
X-99243Y-259619D01*
X-97038Y-257952D01*
X-94518Y-257535D01*
X-91998Y-257952D01*
X-89793Y-259619D01*
X-87903Y-262118D01*
X-86643Y-265035D01*
X-86013Y-268368D01*
Y-271702D01*
X-86643Y-275035D01*
X-87903Y-277952D01*
X-89793Y-280452D01*
X-91998Y-282118D01*
X-94518Y-282535D01*
G01X-91998Y-275868D02*
X-88218Y-282535D01*
G01X-74673Y-265869D02*
Y-277535D01*
X-73413Y-280452D01*
X-71523Y-282118D01*
X-69318Y-282535D01*
X-67113Y-282118D01*
X-65223Y-280452D01*
X-63963Y-277535D01*
G01Y-282535D02*
Y-265869D01*
G01X-38448Y-282535D02*
Y-265869D01*
G01Y-268785D02*
X-39708Y-267119D01*
X-41598Y-266285D01*
X-43803Y-265869D01*
X-46008Y-266702D01*
X-47898Y-268368D01*
X-49158Y-270869D01*
X-49788Y-274202D01*
X-49158Y-277535D01*
X-47898Y-280036D01*
X-46008Y-281702D01*
X-43803Y-282535D01*
X-41598Y-282118D01*
X-39708Y-280869D01*
X-38448Y-279202D01*
G01X-24273Y-282535D02*
Y-265869D01*
G01Y-270035D02*
X-23013Y-267952D01*
X-21123Y-266285D01*
X-18603Y-265869D01*
X-16398Y-266285D01*
X-14508Y-267952D01*
X-13563Y-270869D01*
Y-282535D01*
G01X6282Y-257535D02*
Y-282535D01*
G01X1872Y-265869D02*
X10692D01*
G01X37152Y-282535D02*
Y-265869D01*
G01Y-268785D02*
X35892Y-267119D01*
X34002Y-266285D01*
X31797Y-265869D01*
X29592Y-266702D01*
X27702Y-268368D01*
X26442Y-270869D01*
X25812Y-274202D01*
X26442Y-277535D01*
X27702Y-280036D01*
X29592Y-281702D01*
X31797Y-282535D01*
X34002Y-282118D01*
X35892Y-280869D01*
X37152Y-279202D01*
G01X-71000Y48193D02*
X-67900D01*
Y47427D01*
X-68055Y47120D01*
X-68262Y46890D01*
X-68572Y46698D01*
X-68933Y46545D01*
X-69450Y46507D01*
X-69967Y46545D01*
X-70328Y46698D01*
X-70638Y46890D01*
X-70845Y47120D01*
X-71000Y47427D01*
Y48193D01*
G01Y45208D02*
X-67900Y44250D01*
X-71000Y43292D01*
G01X-69915Y43637D02*
Y44863D01*
G01X-67900Y41150D02*
X-68003Y41457D01*
X-68262Y41687D01*
X-68572Y41840D01*
X-68985Y41955D01*
X-69450Y41993D01*
X-69915Y41955D01*
X-70328Y41840D01*
X-70638Y41687D01*
X-70897Y41457D01*
X-71000Y41150D01*
X-70897Y40843D01*
X-70638Y40613D01*
X-70328Y40460D01*
X-69915Y40345D01*
X-69450Y40307D01*
X-68985Y40345D01*
X-68572Y40460D01*
X-68262Y40613D01*
X-68003Y40843D01*
X-67900Y41150D01*
G01X-71000Y38778D02*
X-67900D01*
Y37322D01*
G01X-69398Y37858D02*
Y38778D01*
G01X-67900Y34950D02*
X-68003Y35257D01*
X-68262Y35487D01*
X-68572Y35640D01*
X-68985Y35755D01*
X-69450Y35793D01*
X-69915Y35755D01*
X-70328Y35640D01*
X-70638Y35487D01*
X-70897Y35257D01*
X-71000Y34950D01*
X-70897Y34643D01*
X-70638Y34413D01*
X-70328Y34260D01*
X-69915Y34145D01*
X-69450Y34107D01*
X-68985Y34145D01*
X-68572Y34260D01*
X-68262Y34413D01*
X-68003Y34643D01*
X-67900Y34950D01*
G01Y31850D02*
X-71000D01*
G01X-67900Y32732D02*
Y30968D01*
G01X-71000Y28750D02*
X-69605D01*
X-67900Y29517D01*
G01Y27983D02*
X-69605Y28750D01*
G01X-69347Y25343D02*
X-69192Y25190D01*
X-68933Y25075D01*
X-68572Y24998D01*
X-68262Y25075D01*
X-68055Y25228D01*
X-67900Y25497D01*
Y26532D01*
X-71000D01*
Y25267D01*
X-70793Y24998D01*
X-70483Y24845D01*
X-70122Y24768D01*
X-69760Y24845D01*
X-69450Y25075D01*
X-69347Y25343D01*
Y26532D01*
G01X-71000Y22090D02*
X-67900D01*
X-70122Y23508D01*
Y21592D01*
G01X-71000Y20293D02*
X-67900D01*
Y19527D01*
X-68055Y19220D01*
X-68262Y18990D01*
X-68572Y18798D01*
X-68933Y18645D01*
X-69450Y18607D01*
X-69967Y18645D01*
X-70328Y18798D01*
X-70638Y18990D01*
X-70845Y19220D01*
X-71000Y19527D01*
Y20293D01*
G01X-67900Y16350D02*
X-68003Y16657D01*
X-68262Y16887D01*
X-68572Y17040D01*
X-68985Y17155D01*
X-69450Y17193D01*
X-69915Y17155D01*
X-70328Y17040D01*
X-70638Y16887D01*
X-70897Y16657D01*
X-71000Y16350D01*
X-70897Y16043D01*
X-70638Y15813D01*
X-70328Y15660D01*
X-69915Y15545D01*
X-69450Y15507D01*
X-68985Y15545D01*
X-68572Y15660D01*
X-68262Y15813D01*
X-68003Y16043D01*
X-67900Y16350D01*
G01X4870Y83670D02*
G03X55512Y58661I19146J-25009D01*
G01X6063Y27953D02*
X24567D01*
Y4331D01*
X21221D01*
Y-393D01*
G02X15315Y-6299I-5906J0D01*
G02X9409Y-393I0J5906D01*
G01Y4331D01*
X6063D01*
Y27953D01*
G01X2807Y29114D02*
Y32214D01*
X3573D01*
X3880Y32059D01*
X4110Y31852D01*
X4302Y31542D01*
X4455Y31181D01*
X4493Y30664D01*
X4455Y30147D01*
X4302Y29786D01*
X4110Y29476D01*
X3880Y29269D01*
X3573Y29114D01*
X2807D01*
G01X6022Y31697D02*
X6252Y32007D01*
X6520Y32162D01*
X6827Y32214D01*
X7210Y32111D01*
X7478Y31852D01*
X7555Y31542D01*
X7517Y31232D01*
X7363Y30974D01*
X6597Y30457D01*
X6252Y30096D01*
X6022Y29579D01*
X5945Y29114D01*
X7555D01*
G01X8900Y116100D02*
X15100D01*
Y112900D01*
X8900D01*
Y116100D01*
G01X2183Y102000D02*
Y105100D01*
X3142D01*
X3448Y104945D01*
X3640Y104738D01*
X3717Y104325D01*
X3640Y103912D01*
X3410Y103653D01*
X3142Y103498D01*
X2183D01*
G01X3142D02*
X3717Y102000D01*
G01X5207Y102465D02*
X5437Y102207D01*
X5705Y102052D01*
X6050Y102000D01*
X6395Y102103D01*
X6663Y102310D01*
X6855Y102672D01*
X6893Y103085D01*
X6817Y103498D01*
X6625Y103757D01*
X6357Y103963D01*
X6088Y104015D01*
X5820Y103963D01*
X5475Y103757D01*
X5590Y105100D01*
X6625D01*
G01X8900D02*
X15100D01*
Y101900D01*
X8900D01*
Y105100D01*
G01X2183Y98000D02*
Y101100D01*
X3142D01*
X3448Y100945D01*
X3640Y100738D01*
X3717Y100325D01*
X3640Y99912D01*
X3410Y99653D01*
X3142Y99498D01*
X2183D01*
G01X3142D02*
X3717Y98000D01*
G01X6050D02*
X6318Y98052D01*
X6625Y98207D01*
X6817Y98465D01*
X6893Y98827D01*
X6817Y99188D01*
X6587Y99498D01*
X6242Y99653D01*
X5858D01*
X5628Y99757D01*
X5437Y100015D01*
X5360Y100377D01*
X5475Y100738D01*
X5743Y100997D01*
X6050Y101100D01*
X6357Y100997D01*
X6625Y100738D01*
X6740Y100377D01*
X6663Y100015D01*
X6472Y99757D01*
X6242Y99653D01*
X5858D01*
X5513Y99498D01*
X5283Y99188D01*
X5207Y98827D01*
X5283Y98465D01*
X5475Y98207D01*
X5782Y98052D01*
X6050Y98000D01*
G01X15100Y97900D02*
X8900D01*
Y101100D01*
X15100D01*
Y97900D01*
G01Y108900D02*
X8900D01*
Y112100D01*
X15100D01*
Y108900D01*
G01X8183Y121500D02*
Y124600D01*
X9142D01*
X9448Y124445D01*
X9640Y124238D01*
X9717Y123825D01*
X9640Y123412D01*
X9410Y123153D01*
X9142Y122998D01*
X8183D01*
G01X9142D02*
X9717Y121500D01*
G01X11398Y121862D02*
X11667Y121603D01*
X11973Y121500D01*
X12280Y121603D01*
X12548Y121913D01*
X12740Y122378D01*
X12817Y122843D01*
Y123412D01*
X12740Y123877D01*
X12548Y124290D01*
X12318Y124497D01*
X12050Y124600D01*
X11743Y124497D01*
X11513Y124290D01*
X11360Y123980D01*
X11283Y123567D01*
X11360Y123205D01*
X11552Y122843D01*
X11782Y122637D01*
X12050Y122585D01*
X12357Y122688D01*
X12587Y122947D01*
X12817Y123412D01*
G01X5133Y117000D02*
Y120100D01*
X6092D01*
X6398Y119945D01*
X6590Y119738D01*
X6667Y119325D01*
X6590Y118912D01*
X6360Y118653D01*
X6092Y118498D01*
X5133D01*
G01X6092D02*
X6667Y117000D01*
G01X9000D02*
Y120100D01*
X8540Y119480D01*
G01Y117000D02*
X9460D01*
G01X11372Y119583D02*
X11602Y119893D01*
X11870Y120048D01*
X12177Y120100D01*
X12560Y119997D01*
X12828Y119738D01*
X12905Y119428D01*
X12867Y119118D01*
X12713Y118860D01*
X11947Y118343D01*
X11602Y117982D01*
X11372Y117465D01*
X11295Y117000D01*
X12905D01*
G01X10500Y170000D02*
X116799D01*
Y146378D01*
X10500D01*
Y170000D01*
G01X2133Y194000D02*
Y197100D01*
X3092D01*
X3398Y196945D01*
X3590Y196738D01*
X3667Y196325D01*
X3590Y195912D01*
X3360Y195653D01*
X3092Y195498D01*
X2133D01*
G01X3092D02*
X3667Y194000D01*
G01X5157Y194465D02*
X5387Y194207D01*
X5655Y194052D01*
X6000Y194000D01*
X6345Y194103D01*
X6613Y194310D01*
X6805Y194672D01*
X6843Y195085D01*
X6767Y195498D01*
X6575Y195757D01*
X6307Y195963D01*
X6038Y196015D01*
X5770Y195963D01*
X5425Y195757D01*
X5540Y197100D01*
X6575D01*
G01X9023Y194000D02*
X9100Y194672D01*
X9215Y195240D01*
X9368Y195757D01*
X9560Y196325D01*
X9867Y197100D01*
X8333D01*
G01X12400Y197600D02*
X18600D01*
Y194400D01*
X12400D01*
Y197600D01*
G01X2133Y186000D02*
Y189100D01*
X3092D01*
X3398Y188945D01*
X3590Y188738D01*
X3667Y188325D01*
X3590Y187912D01*
X3360Y187653D01*
X3092Y187498D01*
X2133D01*
G01X3092D02*
X3667Y186000D01*
G01X5157Y186465D02*
X5387Y186207D01*
X5655Y186052D01*
X6000Y186000D01*
X6345Y186103D01*
X6613Y186310D01*
X6805Y186672D01*
X6843Y187085D01*
X6767Y187498D01*
X6575Y187757D01*
X6307Y187963D01*
X6038Y188015D01*
X5770Y187963D01*
X5425Y187757D01*
X5540Y189100D01*
X6575D01*
G01X8372Y187292D02*
X8640Y187653D01*
X8870Y187860D01*
X9177Y187963D01*
X9445Y187860D01*
X9637Y187653D01*
X9790Y187343D01*
X9828Y186982D01*
X9790Y186672D01*
X9637Y186362D01*
X9407Y186103D01*
X9138Y186000D01*
X8832Y186103D01*
X8563Y186413D01*
X8410Y186878D01*
X8372Y187395D01*
X8448Y188067D01*
X8563Y188428D01*
X8755Y188790D01*
X9023Y189048D01*
X9292Y189100D01*
X9560Y188997D01*
X9752Y188738D01*
G01X12400Y189600D02*
X18600D01*
Y186400D01*
X12400D01*
Y189600D01*
G01X2133Y198000D02*
Y201100D01*
X3092D01*
X3398Y200945D01*
X3590Y200738D01*
X3667Y200325D01*
X3590Y199912D01*
X3360Y199653D01*
X3092Y199498D01*
X2133D01*
G01X3092D02*
X3667Y198000D01*
G01X5272Y199292D02*
X5540Y199653D01*
X5770Y199860D01*
X6077Y199963D01*
X6345Y199860D01*
X6537Y199653D01*
X6690Y199343D01*
X6728Y198982D01*
X6690Y198672D01*
X6537Y198362D01*
X6307Y198103D01*
X6038Y198000D01*
X5732Y198103D01*
X5463Y198413D01*
X5310Y198878D01*
X5272Y199395D01*
X5348Y200067D01*
X5463Y200428D01*
X5655Y200790D01*
X5923Y201048D01*
X6192Y201100D01*
X6460Y200997D01*
X6652Y200738D01*
G01X8257Y198620D02*
X8487Y198258D01*
X8793Y198052D01*
X9138Y198000D01*
X9445Y198052D01*
X9752Y198310D01*
X9943Y198620D01*
X9982Y198930D01*
X9905Y199292D01*
X9637Y199550D01*
X9368Y199653D01*
X9023D01*
G01X9368D02*
X9598Y199808D01*
X9790Y200067D01*
X9867Y200377D01*
X9790Y200687D01*
X9598Y200945D01*
X9253Y201100D01*
X8908Y201048D01*
X8563Y200842D01*
G01X12400Y201600D02*
X18600D01*
Y198400D01*
X12400D01*
Y201600D01*
G01X2133Y190000D02*
Y193100D01*
X3092D01*
X3398Y192945D01*
X3590Y192738D01*
X3667Y192325D01*
X3590Y191912D01*
X3360Y191653D01*
X3092Y191498D01*
X2133D01*
G01X3092D02*
X3667Y190000D01*
G01X5272Y191292D02*
X5540Y191653D01*
X5770Y191860D01*
X6077Y191963D01*
X6345Y191860D01*
X6537Y191653D01*
X6690Y191343D01*
X6728Y190982D01*
X6690Y190672D01*
X6537Y190362D01*
X6307Y190103D01*
X6038Y190000D01*
X5732Y190103D01*
X5463Y190413D01*
X5310Y190878D01*
X5272Y191395D01*
X5348Y192067D01*
X5463Y192428D01*
X5655Y192790D01*
X5923Y193048D01*
X6192Y193100D01*
X6460Y192997D01*
X6652Y192738D01*
G01X8372Y192583D02*
X8602Y192893D01*
X8870Y193048D01*
X9177Y193100D01*
X9560Y192997D01*
X9828Y192738D01*
X9905Y192428D01*
X9867Y192118D01*
X9713Y191860D01*
X8947Y191343D01*
X8602Y190982D01*
X8372Y190465D01*
X8295Y190000D01*
X9905D01*
G01X18600Y190400D02*
X12400D01*
Y193600D01*
X18600D01*
Y190400D01*
G01X2133Y182000D02*
Y185100D01*
X3092D01*
X3398Y184945D01*
X3590Y184738D01*
X3667Y184325D01*
X3590Y183912D01*
X3360Y183653D01*
X3092Y183498D01*
X2133D01*
G01X3092D02*
X3667Y182000D01*
G01X5272Y183292D02*
X5540Y183653D01*
X5770Y183860D01*
X6077Y183963D01*
X6345Y183860D01*
X6537Y183653D01*
X6690Y183343D01*
X6728Y182982D01*
X6690Y182672D01*
X6537Y182362D01*
X6307Y182103D01*
X6038Y182000D01*
X5732Y182103D01*
X5463Y182413D01*
X5310Y182878D01*
X5272Y183395D01*
X5348Y184067D01*
X5463Y184428D01*
X5655Y184790D01*
X5923Y185048D01*
X6192Y185100D01*
X6460Y184997D01*
X6652Y184738D01*
G01X9100Y182000D02*
Y185100D01*
X8640Y184480D01*
G01Y182000D02*
X9560D01*
G01X18600Y182400D02*
X12400D01*
Y185600D01*
X18600D01*
Y182400D01*
G01X2133Y202000D02*
Y205100D01*
X3092D01*
X3398Y204945D01*
X3590Y204738D01*
X3667Y204325D01*
X3590Y203912D01*
X3360Y203653D01*
X3092Y203498D01*
X2133D01*
G01X3092D02*
X3667Y202000D01*
G01X5157Y202465D02*
X5387Y202207D01*
X5655Y202052D01*
X6000Y202000D01*
X6345Y202103D01*
X6613Y202310D01*
X6805Y202672D01*
X6843Y203085D01*
X6767Y203498D01*
X6575Y203757D01*
X6307Y203963D01*
X6038Y204015D01*
X5770Y203963D01*
X5425Y203757D01*
X5540Y205100D01*
X6575D01*
G01X9100Y202000D02*
X9368Y202052D01*
X9675Y202207D01*
X9867Y202465D01*
X9943Y202827D01*
X9867Y203188D01*
X9637Y203498D01*
X9292Y203653D01*
X8908D01*
X8678Y203757D01*
X8487Y204015D01*
X8410Y204377D01*
X8525Y204738D01*
X8793Y204997D01*
X9100Y205100D01*
X9407Y204997D01*
X9675Y204738D01*
X9790Y204377D01*
X9713Y204015D01*
X9522Y203757D01*
X9292Y203653D01*
X8908D01*
X8563Y203498D01*
X8333Y203188D01*
X8257Y202827D01*
X8333Y202465D01*
X8525Y202207D01*
X8832Y202052D01*
X9100Y202000D01*
G01X12400Y205600D02*
X18600D01*
Y202400D01*
X12400D01*
Y205600D01*
G01X8633Y218500D02*
Y221600D01*
X9592D01*
X9898Y221445D01*
X10090Y221238D01*
X10167Y220825D01*
X10090Y220412D01*
X9860Y220153D01*
X9592Y219998D01*
X8633D01*
G01X9592D02*
X10167Y218500D01*
G01X11772Y221083D02*
X12002Y221393D01*
X12270Y221548D01*
X12577Y221600D01*
X12960Y221497D01*
X13228Y221238D01*
X13305Y220928D01*
X13267Y220618D01*
X13113Y220360D01*
X12347Y219843D01*
X12002Y219482D01*
X11772Y218965D01*
X11695Y218500D01*
X13305D01*
G01X15523D02*
X15600Y219172D01*
X15715Y219740D01*
X15868Y220257D01*
X16060Y220825D01*
X16367Y221600D01*
X14833D01*
G01X8633Y210500D02*
Y213600D01*
X9592D01*
X9898Y213445D01*
X10090Y213238D01*
X10167Y212825D01*
X10090Y212412D01*
X9860Y212153D01*
X9592Y211998D01*
X8633D01*
G01X9592D02*
X10167Y210500D01*
G01X11772Y213083D02*
X12002Y213393D01*
X12270Y213548D01*
X12577Y213600D01*
X12960Y213497D01*
X13228Y213238D01*
X13305Y212928D01*
X13267Y212618D01*
X13113Y212360D01*
X12347Y211843D01*
X12002Y211482D01*
X11772Y210965D01*
X11695Y210500D01*
X13305D01*
G01X14872Y211792D02*
X15140Y212153D01*
X15370Y212360D01*
X15677Y212463D01*
X15945Y212360D01*
X16137Y212153D01*
X16290Y211843D01*
X16328Y211482D01*
X16290Y211172D01*
X16137Y210862D01*
X15907Y210603D01*
X15638Y210500D01*
X15332Y210603D01*
X15063Y210913D01*
X14910Y211378D01*
X14872Y211895D01*
X14948Y212567D01*
X15063Y212928D01*
X15255Y213290D01*
X15523Y213548D01*
X15792Y213600D01*
X16060Y213497D01*
X16252Y213238D01*
G01X8633Y214500D02*
Y217600D01*
X9592D01*
X9898Y217445D01*
X10090Y217238D01*
X10167Y216825D01*
X10090Y216412D01*
X9860Y216153D01*
X9592Y215998D01*
X8633D01*
G01X9592D02*
X10167Y214500D01*
G01X11772Y217083D02*
X12002Y217393D01*
X12270Y217548D01*
X12577Y217600D01*
X12960Y217497D01*
X13228Y217238D01*
X13305Y216928D01*
X13267Y216618D01*
X13113Y216360D01*
X12347Y215843D01*
X12002Y215482D01*
X11772Y214965D01*
X11695Y214500D01*
X13305D01*
G01X14872Y217083D02*
X15102Y217393D01*
X15370Y217548D01*
X15677Y217600D01*
X16060Y217497D01*
X16328Y217238D01*
X16405Y216928D01*
X16367Y216618D01*
X16213Y216360D01*
X15447Y215843D01*
X15102Y215482D01*
X14872Y214965D01*
X14795Y214500D01*
X16405D01*
G01X8633Y206500D02*
Y209600D01*
X9592D01*
X9898Y209445D01*
X10090Y209238D01*
X10167Y208825D01*
X10090Y208412D01*
X9860Y208153D01*
X9592Y207998D01*
X8633D01*
G01X9592D02*
X10167Y206500D01*
G01X11772Y209083D02*
X12002Y209393D01*
X12270Y209548D01*
X12577Y209600D01*
X12960Y209497D01*
X13228Y209238D01*
X13305Y208928D01*
X13267Y208618D01*
X13113Y208360D01*
X12347Y207843D01*
X12002Y207482D01*
X11772Y206965D01*
X11695Y206500D01*
X13305D01*
G01X15600D02*
Y209600D01*
X15140Y208980D01*
G01Y206500D02*
X16060D01*
G01X8633Y226500D02*
Y229600D01*
X9592D01*
X9898Y229445D01*
X10090Y229238D01*
X10167Y228825D01*
X10090Y228412D01*
X9860Y228153D01*
X9592Y227998D01*
X8633D01*
G01X9592D02*
X10167Y226500D01*
G01X11772Y229083D02*
X12002Y229393D01*
X12270Y229548D01*
X12577Y229600D01*
X12960Y229497D01*
X13228Y229238D01*
X13305Y228928D01*
X13267Y228618D01*
X13113Y228360D01*
X12347Y227843D01*
X12002Y227482D01*
X11772Y226965D01*
X11695Y226500D01*
X13305D01*
G01X15600D02*
X15868Y226552D01*
X16175Y226707D01*
X16367Y226965D01*
X16443Y227327D01*
X16367Y227688D01*
X16137Y227998D01*
X15792Y228153D01*
X15408D01*
X15178Y228257D01*
X14987Y228515D01*
X14910Y228877D01*
X15025Y229238D01*
X15293Y229497D01*
X15600Y229600D01*
X15907Y229497D01*
X16175Y229238D01*
X16290Y228877D01*
X16213Y228515D01*
X16022Y228257D01*
X15792Y228153D01*
X15408D01*
X15063Y227998D01*
X14833Y227688D01*
X14757Y227327D01*
X14833Y226965D01*
X15025Y226707D01*
X15332Y226552D01*
X15600Y226500D01*
G01X9133Y242500D02*
Y245600D01*
X10092D01*
X10398Y245445D01*
X10590Y245238D01*
X10667Y244825D01*
X10590Y244412D01*
X10360Y244153D01*
X10092Y243998D01*
X9133D01*
G01X10092D02*
X10667Y242500D01*
G01X12272Y245083D02*
X12502Y245393D01*
X12770Y245548D01*
X13077Y245600D01*
X13460Y245497D01*
X13728Y245238D01*
X13805Y244928D01*
X13767Y244618D01*
X13613Y244360D01*
X12847Y243843D01*
X12502Y243482D01*
X12272Y242965D01*
X12195Y242500D01*
X13805D01*
G01X16560D02*
Y245600D01*
X15142Y243378D01*
X17058D01*
G01X8633Y222500D02*
Y225600D01*
X9592D01*
X9898Y225445D01*
X10090Y225238D01*
X10167Y224825D01*
X10090Y224412D01*
X9860Y224153D01*
X9592Y223998D01*
X8633D01*
G01X9592D02*
X10167Y222500D01*
G01X11772Y225083D02*
X12002Y225393D01*
X12270Y225548D01*
X12577Y225600D01*
X12960Y225497D01*
X13228Y225238D01*
X13305Y224928D01*
X13267Y224618D01*
X13113Y224360D01*
X12347Y223843D01*
X12002Y223482D01*
X11772Y222965D01*
X11695Y222500D01*
X13305D01*
G01X14757Y223120D02*
X14987Y222758D01*
X15293Y222552D01*
X15638Y222500D01*
X15945Y222552D01*
X16252Y222810D01*
X16443Y223120D01*
X16482Y223430D01*
X16405Y223792D01*
X16137Y224050D01*
X15868Y224153D01*
X15523D01*
G01X15868D02*
X16098Y224308D01*
X16290Y224567D01*
X16367Y224877D01*
X16290Y225187D01*
X16098Y225445D01*
X15753Y225600D01*
X15408Y225548D01*
X15063Y225342D01*
G01X9133Y238500D02*
Y241600D01*
X10092D01*
X10398Y241445D01*
X10590Y241238D01*
X10667Y240825D01*
X10590Y240412D01*
X10360Y240153D01*
X10092Y239998D01*
X9133D01*
G01X10092D02*
X10667Y238500D01*
G01X13000D02*
Y241600D01*
X12540Y240980D01*
G01Y238500D02*
X13460D01*
G01X15448Y238862D02*
X15717Y238603D01*
X16023Y238500D01*
X16330Y238603D01*
X16598Y238913D01*
X16790Y239378D01*
X16867Y239843D01*
Y240412D01*
X16790Y240877D01*
X16598Y241290D01*
X16368Y241497D01*
X16100Y241600D01*
X15793Y241497D01*
X15563Y241290D01*
X15410Y240980D01*
X15333Y240567D01*
X15410Y240205D01*
X15602Y239843D01*
X15832Y239637D01*
X16100Y239585D01*
X16407Y239688D01*
X16637Y239947D01*
X16867Y240412D01*
G01X8633Y230500D02*
Y233600D01*
X9592D01*
X9898Y233445D01*
X10090Y233238D01*
X10167Y232825D01*
X10090Y232412D01*
X9860Y232153D01*
X9592Y231998D01*
X8633D01*
G01X9592D02*
X10167Y230500D01*
G01X12500D02*
Y233600D01*
X12040Y232980D01*
G01Y230500D02*
X12960D01*
G01X15600D02*
X15868Y230552D01*
X16175Y230707D01*
X16367Y230965D01*
X16443Y231327D01*
X16367Y231688D01*
X16137Y231998D01*
X15792Y232153D01*
X15408D01*
X15178Y232257D01*
X14987Y232515D01*
X14910Y232877D01*
X15025Y233238D01*
X15293Y233497D01*
X15600Y233600D01*
X15907Y233497D01*
X16175Y233238D01*
X16290Y232877D01*
X16213Y232515D01*
X16022Y232257D01*
X15792Y232153D01*
X15408D01*
X15063Y231998D01*
X14833Y231688D01*
X14757Y231327D01*
X14833Y230965D01*
X15025Y230707D01*
X15332Y230552D01*
X15600Y230500D01*
G01X10293Y237342D02*
X10063Y237497D01*
X9795Y237600D01*
X9488D01*
X9143Y237445D01*
X8875Y237187D01*
X8683Y236877D01*
X8530Y236360D01*
X8492Y235895D01*
X8568Y235430D01*
X8683Y235120D01*
X8913Y234810D01*
X9182Y234603D01*
X9450Y234500D01*
X9718D01*
X9987Y234603D01*
X10217Y234758D01*
X10408Y234965D01*
G01X11822Y235792D02*
X12090Y236153D01*
X12320Y236360D01*
X12627Y236463D01*
X12895Y236360D01*
X13087Y236153D01*
X13240Y235843D01*
X13278Y235482D01*
X13240Y235172D01*
X13087Y234862D01*
X12857Y234603D01*
X12588Y234500D01*
X12282Y234603D01*
X12013Y234913D01*
X11860Y235378D01*
X11822Y235895D01*
X11898Y236567D01*
X12013Y236928D01*
X12205Y237290D01*
X12473Y237548D01*
X12742Y237600D01*
X13010Y237497D01*
X13202Y237238D01*
G01X4345Y265000D02*
Y268100D01*
G01X5955D02*
Y265000D01*
G01Y266550D02*
X4345D01*
G01X8710Y265000D02*
Y268100D01*
X7292Y265878D01*
X9208D01*
G01X23450Y255500D02*
G03I-9450J0D01*
G01X9736Y279449D02*
Y293229D01*
G01X42232Y279449D02*
G02X9736I-16248J0D01*
G01Y293229D02*
G02X42232I16248J0D01*
G01X29685Y27953D02*
X48189D01*
Y4331D01*
X44843D01*
Y-393D01*
G02X38937Y-6299I-5906J0D01*
G02X33031Y-393I0J5906D01*
G01Y4331D01*
X29685D01*
Y27953D01*
G01X19807Y95100D02*
Y92878D01*
X19960Y92413D01*
X20267Y92103D01*
X20650Y92000D01*
X21033Y92103D01*
X21340Y92413D01*
X21493Y92878D01*
Y95100D01*
G01X22907Y92620D02*
X23137Y92258D01*
X23443Y92052D01*
X23788Y92000D01*
X24095Y92052D01*
X24402Y92310D01*
X24593Y92620D01*
X24632Y92930D01*
X24555Y93292D01*
X24287Y93550D01*
X24018Y93653D01*
X23673D01*
G01X24018D02*
X24248Y93808D01*
X24440Y94067D01*
X24517Y94377D01*
X24440Y94687D01*
X24248Y94945D01*
X23903Y95100D01*
X23558Y95048D01*
X23213Y94842D01*
G01X34183Y92000D02*
Y95100D01*
X35142D01*
X35448Y94945D01*
X35640Y94738D01*
X35717Y94325D01*
X35640Y93912D01*
X35410Y93653D01*
X35142Y93498D01*
X34183D01*
G01X35142D02*
X35717Y92000D01*
G01X37973D02*
X38050Y92672D01*
X38165Y93240D01*
X38318Y93757D01*
X38510Y94325D01*
X38817Y95100D01*
X37283D01*
G01X55512Y58661D02*
G03X17604Y89498I-31496J0D01*
G01X17243Y105331D02*
Y96669D01*
X27757D01*
Y105331D01*
X17243D01*
G01Y116331D02*
Y107669D01*
X27757D01*
Y116331D01*
X17243D01*
G01X44600Y96200D02*
X34400D01*
Y100800D01*
X44600D01*
Y96200D01*
G01X34400Y111800D02*
X44600D01*
Y107200D01*
X34400D01*
Y111800D01*
G01X28683Y103500D02*
Y106600D01*
X29642D01*
X29948Y106445D01*
X30140Y106238D01*
X30217Y105825D01*
X30140Y105412D01*
X29910Y105153D01*
X29642Y104998D01*
X28683D01*
G01X29642D02*
X30217Y103500D01*
G01X31822Y104792D02*
X32090Y105153D01*
X32320Y105360D01*
X32627Y105463D01*
X32895Y105360D01*
X33087Y105153D01*
X33240Y104843D01*
X33278Y104482D01*
X33240Y104172D01*
X33087Y103862D01*
X32857Y103603D01*
X32588Y103500D01*
X32282Y103603D01*
X32013Y103913D01*
X31860Y104378D01*
X31822Y104895D01*
X31898Y105567D01*
X32013Y105928D01*
X32205Y106290D01*
X32473Y106548D01*
X32742Y106600D01*
X33010Y106497D01*
X33202Y106238D01*
G01X40600Y101900D02*
X34400D01*
Y105100D01*
X40600D01*
Y101900D01*
G01Y112900D02*
X34400D01*
Y116100D01*
X40600D01*
Y112900D01*
G01X20307Y120600D02*
Y118378D01*
X20460Y117913D01*
X20767Y117603D01*
X21150Y117500D01*
X21533Y117603D01*
X21840Y117913D01*
X21993Y118378D01*
Y120600D01*
G01X24710Y117500D02*
Y120600D01*
X23292Y118378D01*
X25208D01*
G01X34633Y117500D02*
Y120600D01*
X35592D01*
X35898Y120445D01*
X36090Y120238D01*
X36167Y119825D01*
X36090Y119412D01*
X35860Y119153D01*
X35592Y118998D01*
X34633D01*
G01X35592D02*
X36167Y117500D01*
G01X38500D02*
Y120600D01*
X38040Y119980D01*
G01Y117500D02*
X38960D01*
G01X41600D02*
Y120600D01*
X41140Y119980D01*
G01Y117500D02*
X42060D01*
G01X34633Y121500D02*
Y124600D01*
X35592D01*
X35898Y124445D01*
X36090Y124238D01*
X36167Y123825D01*
X36090Y123412D01*
X35860Y123153D01*
X35592Y122998D01*
X34633D01*
G01X35592D02*
X36167Y121500D01*
G01X38500D02*
Y124600D01*
X38040Y123980D01*
G01Y121500D02*
X38960D01*
G01X41600Y124600D02*
X41293Y124497D01*
X41063Y124238D01*
X40910Y123928D01*
X40795Y123515D01*
X40757Y123050D01*
X40795Y122585D01*
X40910Y122172D01*
X41063Y121862D01*
X41293Y121603D01*
X41600Y121500D01*
X41907Y121603D01*
X42137Y121862D01*
X42290Y122172D01*
X42405Y122585D01*
X42443Y123050D01*
X42405Y123515D01*
X42290Y123928D01*
X42137Y124238D01*
X41907Y124497D01*
X41600Y124600D01*
G01X21873Y157658D02*
Y165158D01*
X24113D01*
X24860Y164783D01*
X25420Y163908D01*
X25607Y162908D01*
X25420Y161908D01*
X24953Y161158D01*
X24113Y160783D01*
X21873D01*
G01X29560Y157408D02*
X32920Y165158D01*
G01X36593Y157658D02*
Y165158D01*
X40887Y157658D01*
Y165158D01*
G01X39000Y199500D02*
X35157Y203343D01*
X31926D01*
Y183657D01*
X46074D01*
Y203343D01*
X42843D01*
X39000Y199500D01*
G01X26600Y219900D02*
X20400D01*
Y223100D01*
X26600D01*
Y219900D01*
G01Y211900D02*
X20400D01*
Y215100D01*
X26600D01*
Y211900D01*
G01X20400Y219100D02*
X26600D01*
Y215900D01*
X20400D01*
Y219100D01*
G01Y211100D02*
X26600D01*
Y207900D01*
X20400D01*
Y211100D01*
G01X26600Y227900D02*
X20400D01*
Y231100D01*
X26600D01*
Y227900D01*
G01X20400Y227100D02*
X26600D01*
Y223900D01*
X20400D01*
Y227100D01*
G01X26600Y239900D02*
X20400D01*
Y243100D01*
X26600D01*
Y239900D01*
G01Y231900D02*
X20400D01*
Y235100D01*
X26600D01*
Y231900D01*
G01Y235900D02*
X20400D01*
Y239100D01*
X26600D01*
Y235900D01*
G01X34807Y252600D02*
Y250378D01*
X34960Y249913D01*
X35267Y249603D01*
X35650Y249500D01*
X36033Y249603D01*
X36340Y249913D01*
X36493Y250378D01*
Y252600D01*
G01X37907Y249965D02*
X38137Y249707D01*
X38405Y249552D01*
X38750Y249500D01*
X39095Y249603D01*
X39363Y249810D01*
X39555Y250172D01*
X39593Y250585D01*
X39517Y250998D01*
X39325Y251257D01*
X39057Y251463D01*
X38788Y251515D01*
X38520Y251463D01*
X38175Y251257D01*
X38290Y252600D01*
X39325D01*
G01X26600Y243900D02*
X20400D01*
Y247100D01*
X26600D01*
Y243900D01*
G01X53700Y31299D02*
X81260D01*
Y6299D01*
X73582D01*
Y1771D01*
G02X67480Y-4331I-6102J0D01*
G02X61378Y1771I0J6102D01*
G01Y6299D01*
X53700D01*
Y31299D01*
G01X48307Y27500D02*
Y30600D01*
X49073D01*
X49380Y30445D01*
X49610Y30238D01*
X49802Y29928D01*
X49955Y29567D01*
X49993Y29050D01*
X49955Y28533D01*
X49802Y28172D01*
X49610Y27862D01*
X49380Y27655D01*
X49073Y27500D01*
X48307D01*
G01X52250D02*
Y30600D01*
X51790Y29980D01*
G01Y27500D02*
X52710D01*
G01X41807Y29114D02*
Y32214D01*
X42573D01*
X42880Y32059D01*
X43110Y31852D01*
X43302Y31542D01*
X43455Y31181D01*
X43493Y30664D01*
X43455Y30147D01*
X43302Y29786D01*
X43110Y29476D01*
X42880Y29269D01*
X42573Y29114D01*
X41807D01*
G01X44907Y29734D02*
X45137Y29372D01*
X45443Y29166D01*
X45788Y29114D01*
X46095Y29166D01*
X46402Y29424D01*
X46593Y29734D01*
X46632Y30044D01*
X46555Y30406D01*
X46287Y30664D01*
X46018Y30767D01*
X45673D01*
G01X46018D02*
X46248Y30922D01*
X46440Y31181D01*
X46517Y31491D01*
X46440Y31801D01*
X46248Y32059D01*
X45903Y32214D01*
X45558Y32162D01*
X45213Y31956D01*
G01X50607Y39100D02*
Y36878D01*
X50760Y36413D01*
X51067Y36103D01*
X51450Y36000D01*
X51833Y36103D01*
X52140Y36413D01*
X52293Y36878D01*
Y39100D01*
G01X54550Y36000D02*
Y39100D01*
X54090Y38480D01*
G01Y36000D02*
X55010D01*
G01X71594Y53490D02*
Y41009D01*
X56240D01*
Y53687D01*
X71594D01*
G01X56183Y36000D02*
Y39100D01*
X57142D01*
X57448Y38945D01*
X57640Y38738D01*
X57717Y38325D01*
X57640Y37912D01*
X57410Y37653D01*
X57142Y37498D01*
X56183D01*
G01X57142D02*
X57717Y36000D01*
G01X60050D02*
Y39100D01*
X59590Y38480D01*
G01Y36000D02*
X60510D01*
G01X54845Y70500D02*
Y73600D01*
G01X56455D02*
Y70500D01*
G01Y72050D02*
X54845D01*
G01X58098Y70862D02*
X58367Y70603D01*
X58673Y70500D01*
X58980Y70603D01*
X59248Y70913D01*
X59440Y71378D01*
X59517Y71843D01*
Y72412D01*
X59440Y72877D01*
X59248Y73290D01*
X59018Y73497D01*
X58750Y73600D01*
X58443Y73497D01*
X58213Y73290D01*
X58060Y72980D01*
X57983Y72567D01*
X58060Y72205D01*
X58252Y71843D01*
X58482Y71637D01*
X58750Y71585D01*
X59057Y71688D01*
X59287Y71947D01*
X59517Y72412D01*
G01X58500Y63183D02*
X55400D01*
Y64142D01*
X55555Y64448D01*
X55762Y64640D01*
X56175Y64717D01*
X56588Y64640D01*
X56847Y64410D01*
X57002Y64142D01*
Y63183D01*
G01Y64142D02*
X58500Y64717D01*
G01X55917Y66322D02*
X55607Y66552D01*
X55452Y66820D01*
X55400Y67127D01*
X55503Y67510D01*
X55762Y67778D01*
X56072Y67855D01*
X56382Y67817D01*
X56640Y67663D01*
X57157Y66897D01*
X57518Y66552D01*
X58035Y66322D01*
X58500Y66245D01*
Y67855D01*
G01X60000Y91150D02*
X59948Y90843D01*
X59742Y90575D01*
X59432Y90345D01*
X59070Y90192D01*
X58657Y90115D01*
X58243D01*
X57830Y90192D01*
X57468Y90345D01*
X57158Y90575D01*
X56952Y90843D01*
X56900Y91150D01*
X56952Y91457D01*
X57158Y91725D01*
X57468Y91955D01*
X57830Y92108D01*
X58243Y92185D01*
X58657D01*
X59070Y92108D01*
X59432Y91955D01*
X59742Y91725D01*
X59948Y91457D01*
X60000Y91150D01*
G01X59173Y91457D02*
X60000Y91917D01*
G01Y94250D02*
X56900D01*
X57520Y93790D01*
G01X60000D02*
Y94710D01*
G01X49500Y96000D02*
X47169Y93669D01*
Y90560D01*
X55831D01*
Y101440D01*
X47169D01*
Y98331D01*
X49500Y96000D01*
G01X41133Y86000D02*
Y89100D01*
X42092D01*
X42398Y88945D01*
X42590Y88738D01*
X42667Y88325D01*
X42590Y87912D01*
X42360Y87653D01*
X42092Y87498D01*
X41133D01*
G01X42092D02*
X42667Y86000D01*
G01X44157Y86465D02*
X44387Y86207D01*
X44655Y86052D01*
X45000Y86000D01*
X45345Y86103D01*
X45613Y86310D01*
X45805Y86672D01*
X45843Y87085D01*
X45767Y87498D01*
X45575Y87757D01*
X45307Y87963D01*
X45038Y88015D01*
X44770Y87963D01*
X44425Y87757D01*
X44540Y89100D01*
X45575D01*
G01X48100D02*
X47793Y88997D01*
X47563Y88738D01*
X47410Y88428D01*
X47295Y88015D01*
X47257Y87550D01*
X47295Y87085D01*
X47410Y86672D01*
X47563Y86362D01*
X47793Y86103D01*
X48100Y86000D01*
X48407Y86103D01*
X48637Y86362D01*
X48790Y86672D01*
X48905Y87085D01*
X48943Y87550D01*
X48905Y88015D01*
X48790Y88428D01*
X48637Y88738D01*
X48407Y88997D01*
X48100Y89100D01*
G01X56100Y85900D02*
X49900D01*
Y89100D01*
X56100D01*
Y85900D01*
G01X51633Y76500D02*
Y79600D01*
X52592D01*
X52898Y79445D01*
X53090Y79238D01*
X53167Y78825D01*
X53090Y78412D01*
X52860Y78153D01*
X52592Y77998D01*
X51633D01*
G01X52592D02*
X53167Y76500D01*
G01X55960D02*
Y79600D01*
X54542Y77378D01*
X56458D01*
G01X57757Y77120D02*
X57987Y76758D01*
X58293Y76552D01*
X58638Y76500D01*
X58945Y76552D01*
X59252Y76810D01*
X59443Y77120D01*
X59482Y77430D01*
X59405Y77792D01*
X59137Y78050D01*
X58868Y78153D01*
X58523D01*
G01X58868D02*
X59098Y78308D01*
X59290Y78567D01*
X59367Y78877D01*
X59290Y79187D01*
X59098Y79445D01*
X58753Y79600D01*
X58408Y79548D01*
X58063Y79342D01*
G01X49900Y85100D02*
X56100D01*
Y81900D01*
X49900D01*
Y85100D01*
G01X49633Y112500D02*
Y115600D01*
X50592D01*
X50898Y115445D01*
X51090Y115238D01*
X51167Y114825D01*
X51090Y114412D01*
X50860Y114153D01*
X50592Y113998D01*
X49633D01*
G01X50592D02*
X51167Y112500D01*
G01X53960D02*
Y115600D01*
X52542Y113378D01*
X54458D01*
G01X57060Y112500D02*
Y115600D01*
X55642Y113378D01*
X57558D01*
G01X56100Y108400D02*
X49900D01*
Y111600D01*
X56100D01*
Y108400D01*
G01X45345Y134000D02*
Y137100D01*
G01X46955D02*
Y134000D01*
G01Y135550D02*
X45345D01*
G01X48522Y136583D02*
X48752Y136893D01*
X49020Y137048D01*
X49327Y137100D01*
X49710Y136997D01*
X49978Y136738D01*
X50055Y136428D01*
X50017Y136118D01*
X49863Y135860D01*
X49097Y135343D01*
X48752Y134982D01*
X48522Y134465D01*
X48445Y134000D01*
X50055D01*
G01X70439Y131906D02*
G03I-9450J0D01*
G01X48000Y238000D02*
X42449Y243551D01*
X39742D01*
Y212449D01*
X56258D01*
Y243551D01*
X53551D01*
X48000Y238000D01*
G01X41307Y207600D02*
Y205378D01*
X41460Y204913D01*
X41767Y204603D01*
X42150Y204500D01*
X42533Y204603D01*
X42840Y204913D01*
X42993Y205378D01*
Y207600D01*
G01X44598Y204862D02*
X44867Y204603D01*
X45173Y204500D01*
X45480Y204603D01*
X45748Y204913D01*
X45940Y205378D01*
X46017Y205843D01*
Y206412D01*
X45940Y206877D01*
X45748Y207290D01*
X45518Y207497D01*
X45250Y207600D01*
X44943Y207497D01*
X44713Y207290D01*
X44560Y206980D01*
X44483Y206567D01*
X44560Y206205D01*
X44752Y205843D01*
X44982Y205637D01*
X45250Y205585D01*
X45557Y205688D01*
X45787Y205947D01*
X46017Y206412D01*
G01X54400Y203100D02*
X60600D01*
Y199900D01*
X54400D01*
Y203100D01*
G01X52293Y262342D02*
X52063Y262497D01*
X51795Y262600D01*
X51488D01*
X51143Y262445D01*
X50875Y262187D01*
X50683Y261877D01*
X50530Y261360D01*
X50492Y260895D01*
X50568Y260430D01*
X50683Y260120D01*
X50913Y259810D01*
X51182Y259603D01*
X51450Y259500D01*
X51718D01*
X51987Y259603D01*
X52217Y259758D01*
X52408Y259965D01*
G01X53707Y260120D02*
X53937Y259758D01*
X54243Y259552D01*
X54588Y259500D01*
X54895Y259552D01*
X55202Y259810D01*
X55393Y260120D01*
X55432Y260430D01*
X55355Y260792D01*
X55087Y261050D01*
X54818Y261153D01*
X54473D01*
G01X54818D02*
X55048Y261308D01*
X55240Y261567D01*
X55317Y261877D01*
X55240Y262187D01*
X55048Y262445D01*
X54703Y262600D01*
X54358Y262548D01*
X54013Y262342D01*
G01X67600Y258700D02*
X57400D01*
Y263300D01*
X67600D01*
Y258700D01*
G01X53133Y245500D02*
Y248600D01*
X54092D01*
X54398Y248445D01*
X54590Y248238D01*
X54667Y247825D01*
X54590Y247412D01*
X54360Y247153D01*
X54092Y246998D01*
X53133D01*
G01X54092D02*
X54667Y245500D01*
G01X57000D02*
Y248600D01*
X56540Y247980D01*
G01Y245500D02*
X57460D01*
G01X59257Y246120D02*
X59487Y245758D01*
X59793Y245552D01*
X60138Y245500D01*
X60445Y245552D01*
X60752Y245810D01*
X60943Y246120D01*
X60982Y246430D01*
X60905Y246792D01*
X60637Y247050D01*
X60368Y247153D01*
X60023D01*
G01X60368D02*
X60598Y247308D01*
X60790Y247567D01*
X60867Y247877D01*
X60790Y248187D01*
X60598Y248445D01*
X60253Y248600D01*
X59908Y248548D01*
X59563Y248342D01*
G01X47100Y245400D02*
X40900D01*
Y248600D01*
X47100D01*
Y245400D01*
G01X52293Y266842D02*
X52063Y266997D01*
X51795Y267100D01*
X51488D01*
X51143Y266945D01*
X50875Y266687D01*
X50683Y266377D01*
X50530Y265860D01*
X50492Y265395D01*
X50568Y264930D01*
X50683Y264620D01*
X50913Y264310D01*
X51182Y264103D01*
X51450Y264000D01*
X51718D01*
X51987Y264103D01*
X52217Y264258D01*
X52408Y264465D01*
G01X55010Y264000D02*
Y267100D01*
X53592Y264878D01*
X55508D01*
G01X54883Y273620D02*
X55075Y273310D01*
X55305Y273103D01*
X55573Y273000D01*
X55880Y273103D01*
X56110Y273310D01*
X56340Y273620D01*
X56417Y274033D01*
Y276100D01*
G01X58750Y273000D02*
Y276100D01*
X58290Y275480D01*
G01Y273000D02*
X59210D01*
G01X42232Y293229D02*
Y279449D01*
G01X38345Y306000D02*
Y309100D01*
G01X39955D02*
Y306000D01*
G01Y307550D02*
X38345D01*
G01X42250Y306000D02*
Y309100D01*
X41790Y308480D01*
G01Y306000D02*
X42710D01*
G01X44622Y308583D02*
X44852Y308893D01*
X45120Y309048D01*
X45427Y309100D01*
X45810Y308997D01*
X46078Y308738D01*
X46155Y308428D01*
X46117Y308118D01*
X45963Y307860D01*
X45197Y307343D01*
X44852Y306982D01*
X44622Y306465D01*
X44545Y306000D01*
X46155D01*
G01X76832Y-262235D02*
Y-270235D01*
X80832D01*
G01X88632D02*
Y-264902D01*
G01Y-265835D02*
X88232Y-265302D01*
X87632Y-265035D01*
X86932Y-264902D01*
X86232Y-265168D01*
X85632Y-265702D01*
X85232Y-266502D01*
X85032Y-267568D01*
X85232Y-268635D01*
X85632Y-269435D01*
X86232Y-269968D01*
X86932Y-270235D01*
X87632Y-270102D01*
X88232Y-269702D01*
X88632Y-269169D01*
G01X92732Y-272635D02*
X93332Y-272902D01*
X94132Y-272635D01*
X94632Y-272102D01*
X95032Y-271435D01*
X95632Y-269302D01*
X96932Y-264902D01*
G01X93732D02*
X95632Y-269302D01*
G01X101332Y-266635D02*
X104532D01*
X104232Y-265702D01*
X103732Y-265168D01*
X103032Y-264902D01*
X102332Y-265035D01*
X101732Y-265435D01*
X101332Y-266368D01*
X101132Y-267169D01*
Y-267968D01*
X101332Y-268768D01*
X101832Y-269568D01*
X102432Y-270102D01*
X103132Y-270235D01*
X103832Y-269968D01*
X104532Y-269169D01*
G01X109432Y-270235D02*
Y-264902D01*
G01Y-265968D02*
X109932Y-265435D01*
X110432Y-265035D01*
X111132Y-264902D01*
X111632Y-265035D01*
X112232Y-265435D01*
G01X61400Y39400D02*
X71600D01*
Y34800D01*
X61400D01*
Y39400D01*
G01X73455Y49681D02*
X80055D01*
Y36681D01*
X73455D01*
Y49681D01*
G01X76107Y68600D02*
Y66378D01*
X76260Y65913D01*
X76567Y65603D01*
X76950Y65500D01*
X77333Y65603D01*
X77640Y65913D01*
X77793Y66378D01*
Y68600D01*
G01X79322Y68083D02*
X79552Y68393D01*
X79820Y68548D01*
X80127Y68600D01*
X80510Y68497D01*
X80778Y68238D01*
X80855Y67928D01*
X80817Y67618D01*
X80663Y67360D01*
X79897Y66843D01*
X79552Y66482D01*
X79322Y65965D01*
X79245Y65500D01*
X80855D01*
G01X65374Y51825D02*
Y64306D01*
X80728D01*
Y51628D01*
X65374D01*
G01X59683Y66000D02*
Y69100D01*
X60642D01*
X60948Y68945D01*
X61140Y68738D01*
X61217Y68325D01*
X61140Y67912D01*
X60910Y67653D01*
X60642Y67498D01*
X59683D01*
G01X60642D02*
X61217Y66000D01*
G01X64010D02*
Y69100D01*
X62592Y66878D01*
X64508D01*
G01X65400Y69100D02*
X71600D01*
Y65900D01*
X65400D01*
Y69100D01*
G01X61100Y62100D02*
Y55900D01*
X57900D01*
Y62100D01*
X61100D01*
G01X80406Y78537D02*
Y74463D01*
X68594D01*
Y78537D01*
X80406D01*
G01X73900Y92600D02*
X80100D01*
Y89400D01*
X73900D01*
Y92600D01*
G01X72100Y85400D02*
X65900D01*
Y88600D01*
X72100D01*
Y85400D01*
G01X73900Y88600D02*
X80100D01*
Y85400D01*
X73900D01*
Y88600D01*
G01X64000Y81633D02*
X60900D01*
Y82592D01*
X61055Y82898D01*
X61262Y83090D01*
X61675Y83167D01*
X62088Y83090D01*
X62347Y82860D01*
X62502Y82592D01*
Y81633D01*
G01Y82592D02*
X64000Y83167D01*
G01X61417Y84772D02*
X61107Y85002D01*
X60952Y85270D01*
X60900Y85577D01*
X61003Y85960D01*
X61262Y86228D01*
X61572Y86305D01*
X61882Y86267D01*
X62140Y86113D01*
X62657Y85347D01*
X63018Y85002D01*
X63535Y84772D01*
X64000Y84695D01*
Y86305D01*
G01X63638Y87948D02*
X63897Y88217D01*
X64000Y88523D01*
X63897Y88830D01*
X63587Y89098D01*
X63122Y89290D01*
X62657Y89367D01*
X62088D01*
X61623Y89290D01*
X61210Y89098D01*
X61003Y88868D01*
X60900Y88600D01*
X61003Y88293D01*
X61210Y88063D01*
X61520Y87910D01*
X61933Y87833D01*
X62295Y87910D01*
X62657Y88102D01*
X62863Y88332D01*
X62915Y88600D01*
X62812Y88907D01*
X62553Y89137D01*
X62088Y89367D01*
G01X66600Y80600D02*
Y74400D01*
X63400D01*
Y80600D01*
X66600D01*
G01X65900Y92600D02*
X72100D01*
Y89400D01*
X65900D01*
Y92600D01*
G01X61000Y103633D02*
X57900D01*
Y104592D01*
X58055Y104898D01*
X58262Y105090D01*
X58675Y105167D01*
X59088Y105090D01*
X59347Y104860D01*
X59502Y104592D01*
Y103633D01*
G01Y104592D02*
X61000Y105167D01*
G01Y107960D02*
X57900D01*
X60122Y106542D01*
Y108458D01*
G01X60535Y109757D02*
X60793Y109987D01*
X60948Y110255D01*
X61000Y110600D01*
X60897Y110945D01*
X60690Y111213D01*
X60328Y111405D01*
X59915Y111443D01*
X59502Y111367D01*
X59243Y111175D01*
X59037Y110907D01*
X58985Y110638D01*
X59037Y110370D01*
X59243Y110025D01*
X57900Y110140D01*
Y111175D01*
G01X61100Y102100D02*
Y95900D01*
X57900D01*
Y102100D01*
X61100D01*
G01X74633Y106000D02*
Y109100D01*
X75592D01*
X75898Y108945D01*
X76090Y108738D01*
X76167Y108325D01*
X76090Y107912D01*
X75860Y107653D01*
X75592Y107498D01*
X74633D01*
G01X75592D02*
X76167Y106000D01*
G01X77657Y106620D02*
X77887Y106258D01*
X78193Y106052D01*
X78538Y106000D01*
X78845Y106052D01*
X79152Y106310D01*
X79343Y106620D01*
X79382Y106930D01*
X79305Y107292D01*
X79037Y107550D01*
X78768Y107653D01*
X78423D01*
G01X78768D02*
X78998Y107808D01*
X79190Y108067D01*
X79267Y108377D01*
X79190Y108687D01*
X78998Y108945D01*
X78653Y109100D01*
X78308Y109048D01*
X77963Y108842D01*
G01X80872Y107292D02*
X81140Y107653D01*
X81370Y107860D01*
X81677Y107963D01*
X81945Y107860D01*
X82137Y107653D01*
X82290Y107343D01*
X82328Y106982D01*
X82290Y106672D01*
X82137Y106362D01*
X81907Y106103D01*
X81638Y106000D01*
X81332Y106103D01*
X81063Y106413D01*
X80910Y106878D01*
X80872Y107395D01*
X80948Y108067D01*
X81063Y108428D01*
X81255Y108790D01*
X81523Y109048D01*
X81792Y109100D01*
X82060Y108997D01*
X82252Y108738D01*
G01X74633Y110000D02*
Y113100D01*
X75592D01*
X75898Y112945D01*
X76090Y112738D01*
X76167Y112325D01*
X76090Y111912D01*
X75860Y111653D01*
X75592Y111498D01*
X74633D01*
G01X75592D02*
X76167Y110000D01*
G01X77657Y110620D02*
X77887Y110258D01*
X78193Y110052D01*
X78538Y110000D01*
X78845Y110052D01*
X79152Y110310D01*
X79343Y110620D01*
X79382Y110930D01*
X79305Y111292D01*
X79037Y111550D01*
X78768Y111653D01*
X78423D01*
G01X78768D02*
X78998Y111808D01*
X79190Y112067D01*
X79267Y112377D01*
X79190Y112687D01*
X78998Y112945D01*
X78653Y113100D01*
X78308Y113048D01*
X77963Y112842D01*
G01X80757Y110465D02*
X80987Y110207D01*
X81255Y110052D01*
X81600Y110000D01*
X81945Y110103D01*
X82213Y110310D01*
X82405Y110672D01*
X82443Y111085D01*
X82367Y111498D01*
X82175Y111757D01*
X81907Y111963D01*
X81638Y112015D01*
X81370Y111963D01*
X81025Y111757D01*
X81140Y113100D01*
X82175D01*
G01X73900Y96600D02*
X80100D01*
Y93400D01*
X73900D01*
Y96600D01*
G01X64633Y102000D02*
Y105100D01*
X65592D01*
X65898Y104945D01*
X66090Y104738D01*
X66167Y104325D01*
X66090Y103912D01*
X65860Y103653D01*
X65592Y103498D01*
X64633D01*
G01X65592D02*
X66167Y102000D01*
G01X68960D02*
Y105100D01*
X67542Y102878D01*
X69458D01*
G01X71523Y102000D02*
X71600Y102672D01*
X71715Y103240D01*
X71868Y103757D01*
X72060Y104325D01*
X72367Y105100D01*
X70833D01*
G01X64633Y114000D02*
Y117100D01*
X65592D01*
X65898Y116945D01*
X66090Y116738D01*
X66167Y116325D01*
X66090Y115912D01*
X65860Y115653D01*
X65592Y115498D01*
X64633D01*
G01X65592D02*
X66167Y114000D01*
G01X68960D02*
Y117100D01*
X67542Y114878D01*
X69458D01*
G01X70872Y115292D02*
X71140Y115653D01*
X71370Y115860D01*
X71677Y115963D01*
X71945Y115860D01*
X72137Y115653D01*
X72290Y115343D01*
X72328Y114982D01*
X72290Y114672D01*
X72137Y114362D01*
X71907Y114103D01*
X71638Y114000D01*
X71332Y114103D01*
X71063Y114413D01*
X70910Y114878D01*
X70872Y115395D01*
X70948Y116067D01*
X71063Y116428D01*
X71255Y116790D01*
X71523Y117048D01*
X71792Y117100D01*
X72060Y116997D01*
X72252Y116738D01*
G01X72100Y97400D02*
X65900D01*
Y100600D01*
X72100D01*
Y97400D01*
G01X74633Y114000D02*
Y117100D01*
X75592D01*
X75898Y116945D01*
X76090Y116738D01*
X76167Y116325D01*
X76090Y115912D01*
X75860Y115653D01*
X75592Y115498D01*
X74633D01*
G01X75592D02*
X76167Y114000D01*
G01X77657Y114620D02*
X77887Y114258D01*
X78193Y114052D01*
X78538Y114000D01*
X78845Y114052D01*
X79152Y114310D01*
X79343Y114620D01*
X79382Y114930D01*
X79305Y115292D01*
X79037Y115550D01*
X78768Y115653D01*
X78423D01*
G01X78768D02*
X78998Y115808D01*
X79190Y116067D01*
X79267Y116377D01*
X79190Y116687D01*
X78998Y116945D01*
X78653Y117100D01*
X78308Y117048D01*
X77963Y116842D01*
G01X81600Y114000D02*
Y117100D01*
X81140Y116480D01*
G01Y114000D02*
X82060D01*
G01X73900Y100600D02*
X80100D01*
Y97400D01*
X73900D01*
Y100600D01*
G01X74633Y102000D02*
Y105100D01*
X75592D01*
X75898Y104945D01*
X76090Y104738D01*
X76167Y104325D01*
X76090Y103912D01*
X75860Y103653D01*
X75592Y103498D01*
X74633D01*
G01X75592D02*
X76167Y102000D01*
G01X77657Y102620D02*
X77887Y102258D01*
X78193Y102052D01*
X78538Y102000D01*
X78845Y102052D01*
X79152Y102310D01*
X79343Y102620D01*
X79382Y102930D01*
X79305Y103292D01*
X79037Y103550D01*
X78768Y103653D01*
X78423D01*
G01X78768D02*
X78998Y103808D01*
X79190Y104067D01*
X79267Y104377D01*
X79190Y104687D01*
X78998Y104945D01*
X78653Y105100D01*
X78308Y105048D01*
X77963Y104842D01*
G01X81600Y105100D02*
X81293Y104997D01*
X81063Y104738D01*
X80910Y104428D01*
X80795Y104015D01*
X80757Y103550D01*
X80795Y103085D01*
X80910Y102672D01*
X81063Y102362D01*
X81293Y102103D01*
X81600Y102000D01*
X81907Y102103D01*
X82137Y102362D01*
X82290Y102672D01*
X82405Y103085D01*
X82443Y103550D01*
X82405Y104015D01*
X82290Y104428D01*
X82137Y104738D01*
X81907Y104997D01*
X81600Y105100D01*
G01X64633Y110000D02*
Y113100D01*
X65592D01*
X65898Y112945D01*
X66090Y112738D01*
X66167Y112325D01*
X66090Y111912D01*
X65860Y111653D01*
X65592Y111498D01*
X64633D01*
G01X65592D02*
X66167Y110000D01*
G01X68960D02*
Y113100D01*
X67542Y110878D01*
X69458D01*
G01X70948Y110362D02*
X71217Y110103D01*
X71523Y110000D01*
X71830Y110103D01*
X72098Y110413D01*
X72290Y110878D01*
X72367Y111343D01*
Y111912D01*
X72290Y112377D01*
X72098Y112790D01*
X71868Y112997D01*
X71600Y113100D01*
X71293Y112997D01*
X71063Y112790D01*
X70910Y112480D01*
X70833Y112067D01*
X70910Y111705D01*
X71102Y111343D01*
X71332Y111137D01*
X71600Y111085D01*
X71907Y111188D01*
X72137Y111447D01*
X72367Y111912D01*
G01X65900Y96600D02*
X72100D01*
Y93400D01*
X65900D01*
Y96600D01*
G01X64633Y106000D02*
Y109100D01*
X65592D01*
X65898Y108945D01*
X66090Y108738D01*
X66167Y108325D01*
X66090Y107912D01*
X65860Y107653D01*
X65592Y107498D01*
X64633D01*
G01X65592D02*
X66167Y106000D01*
G01X68960D02*
Y109100D01*
X67542Y106878D01*
X69458D01*
G01X71600Y106000D02*
X71868Y106052D01*
X72175Y106207D01*
X72367Y106465D01*
X72443Y106827D01*
X72367Y107188D01*
X72137Y107498D01*
X71792Y107653D01*
X71408D01*
X71178Y107757D01*
X70987Y108015D01*
X70910Y108377D01*
X71025Y108738D01*
X71293Y108997D01*
X71600Y109100D01*
X71907Y108997D01*
X72175Y108738D01*
X72290Y108377D01*
X72213Y108015D01*
X72022Y107757D01*
X71792Y107653D01*
X71408D01*
X71063Y107498D01*
X70833Y107188D01*
X70757Y106827D01*
X70833Y106465D01*
X71025Y106207D01*
X71332Y106052D01*
X71600Y106000D01*
G01X68633Y176000D02*
Y179100D01*
X69592D01*
X69898Y178945D01*
X70090Y178738D01*
X70167Y178325D01*
X70090Y177912D01*
X69860Y177653D01*
X69592Y177498D01*
X68633D01*
G01X69592D02*
X70167Y176000D01*
G01X71657Y176465D02*
X71887Y176207D01*
X72155Y176052D01*
X72500Y176000D01*
X72845Y176103D01*
X73113Y176310D01*
X73305Y176672D01*
X73343Y177085D01*
X73267Y177498D01*
X73075Y177757D01*
X72807Y177963D01*
X72538Y178015D01*
X72270Y177963D01*
X71925Y177757D01*
X72040Y179100D01*
X73075D01*
G01X76060Y176000D02*
Y179100D01*
X74642Y176878D01*
X76558D01*
G01X65600Y175900D02*
X59400D01*
Y179100D01*
X65600D01*
Y175900D01*
G01X68633Y180000D02*
Y183100D01*
X69592D01*
X69898Y182945D01*
X70090Y182738D01*
X70167Y182325D01*
X70090Y181912D01*
X69860Y181653D01*
X69592Y181498D01*
X68633D01*
G01X69592D02*
X70167Y180000D01*
G01X71772Y181292D02*
X72040Y181653D01*
X72270Y181860D01*
X72577Y181963D01*
X72845Y181860D01*
X73037Y181653D01*
X73190Y181343D01*
X73228Y180982D01*
X73190Y180672D01*
X73037Y180362D01*
X72807Y180103D01*
X72538Y180000D01*
X72232Y180103D01*
X71963Y180413D01*
X71810Y180878D01*
X71772Y181395D01*
X71848Y182067D01*
X71963Y182428D01*
X72155Y182790D01*
X72423Y183048D01*
X72692Y183100D01*
X72960Y182997D01*
X73152Y182738D01*
G01X75600Y183100D02*
X75293Y182997D01*
X75063Y182738D01*
X74910Y182428D01*
X74795Y182015D01*
X74757Y181550D01*
X74795Y181085D01*
X74910Y180672D01*
X75063Y180362D01*
X75293Y180103D01*
X75600Y180000D01*
X75907Y180103D01*
X76137Y180362D01*
X76290Y180672D01*
X76405Y181085D01*
X76443Y181550D01*
X76405Y182015D01*
X76290Y182428D01*
X76137Y182738D01*
X75907Y182997D01*
X75600Y183100D01*
G01X65600Y179900D02*
X59400D01*
Y183100D01*
X65600D01*
Y179900D01*
G01X68633Y184000D02*
Y187100D01*
X69592D01*
X69898Y186945D01*
X70090Y186738D01*
X70167Y186325D01*
X70090Y185912D01*
X69860Y185653D01*
X69592Y185498D01*
X68633D01*
G01X69592D02*
X70167Y184000D01*
G01X71657Y184465D02*
X71887Y184207D01*
X72155Y184052D01*
X72500Y184000D01*
X72845Y184103D01*
X73113Y184310D01*
X73305Y184672D01*
X73343Y185085D01*
X73267Y185498D01*
X73075Y185757D01*
X72807Y185963D01*
X72538Y186015D01*
X72270Y185963D01*
X71925Y185757D01*
X72040Y187100D01*
X73075D01*
G01X74948Y184362D02*
X75217Y184103D01*
X75523Y184000D01*
X75830Y184103D01*
X76098Y184413D01*
X76290Y184878D01*
X76367Y185343D01*
Y185912D01*
X76290Y186377D01*
X76098Y186790D01*
X75868Y186997D01*
X75600Y187100D01*
X75293Y186997D01*
X75063Y186790D01*
X74910Y186480D01*
X74833Y186067D01*
X74910Y185705D01*
X75102Y185343D01*
X75332Y185137D01*
X75600Y185085D01*
X75907Y185188D01*
X76137Y185447D01*
X76367Y185912D01*
G01X65600Y183900D02*
X59400D01*
Y187100D01*
X65600D01*
Y183900D01*
G01X68633Y192000D02*
Y195100D01*
X69592D01*
X69898Y194945D01*
X70090Y194738D01*
X70167Y194325D01*
X70090Y193912D01*
X69860Y193653D01*
X69592Y193498D01*
X68633D01*
G01X69592D02*
X70167Y192000D01*
G01X71657Y192465D02*
X71887Y192207D01*
X72155Y192052D01*
X72500Y192000D01*
X72845Y192103D01*
X73113Y192310D01*
X73305Y192672D01*
X73343Y193085D01*
X73267Y193498D01*
X73075Y193757D01*
X72807Y193963D01*
X72538Y194015D01*
X72270Y193963D01*
X71925Y193757D01*
X72040Y195100D01*
X73075D01*
G01X74757Y192465D02*
X74987Y192207D01*
X75255Y192052D01*
X75600Y192000D01*
X75945Y192103D01*
X76213Y192310D01*
X76405Y192672D01*
X76443Y193085D01*
X76367Y193498D01*
X76175Y193757D01*
X75907Y193963D01*
X75638Y194015D01*
X75370Y193963D01*
X75025Y193757D01*
X75140Y195100D01*
X76175D01*
G01X65600Y191900D02*
X59400D01*
Y195100D01*
X65600D01*
Y191900D01*
G01X68633Y188000D02*
Y191100D01*
X69592D01*
X69898Y190945D01*
X70090Y190738D01*
X70167Y190325D01*
X70090Y189912D01*
X69860Y189653D01*
X69592Y189498D01*
X68633D01*
G01X69592D02*
X70167Y188000D01*
G01X71657Y188465D02*
X71887Y188207D01*
X72155Y188052D01*
X72500Y188000D01*
X72845Y188103D01*
X73113Y188310D01*
X73305Y188672D01*
X73343Y189085D01*
X73267Y189498D01*
X73075Y189757D01*
X72807Y189963D01*
X72538Y190015D01*
X72270Y189963D01*
X71925Y189757D01*
X72040Y191100D01*
X73075D01*
G01X74757Y188620D02*
X74987Y188258D01*
X75293Y188052D01*
X75638Y188000D01*
X75945Y188052D01*
X76252Y188310D01*
X76443Y188620D01*
X76482Y188930D01*
X76405Y189292D01*
X76137Y189550D01*
X75868Y189653D01*
X75523D01*
G01X75868D02*
X76098Y189808D01*
X76290Y190067D01*
X76367Y190377D01*
X76290Y190687D01*
X76098Y190945D01*
X75753Y191100D01*
X75408Y191048D01*
X75063Y190842D01*
G01X65600Y187900D02*
X59400D01*
Y191100D01*
X65600D01*
Y187900D01*
G01X68633Y196000D02*
Y199100D01*
X69592D01*
X69898Y198945D01*
X70090Y198738D01*
X70167Y198325D01*
X70090Y197912D01*
X69860Y197653D01*
X69592Y197498D01*
X68633D01*
G01X69592D02*
X70167Y196000D01*
G01X71772Y197292D02*
X72040Y197653D01*
X72270Y197860D01*
X72577Y197963D01*
X72845Y197860D01*
X73037Y197653D01*
X73190Y197343D01*
X73228Y196982D01*
X73190Y196672D01*
X73037Y196362D01*
X72807Y196103D01*
X72538Y196000D01*
X72232Y196103D01*
X71963Y196413D01*
X71810Y196878D01*
X71772Y197395D01*
X71848Y198067D01*
X71963Y198428D01*
X72155Y198790D01*
X72423Y199048D01*
X72692Y199100D01*
X72960Y198997D01*
X73152Y198738D01*
G01X76060Y196000D02*
Y199100D01*
X74642Y196878D01*
X76558D01*
G01X59400Y199100D02*
X65600D01*
Y195900D01*
X59400D01*
Y199100D01*
G01X73133Y209000D02*
Y214000D01*
X74653D01*
X75160Y213750D01*
X75540Y213167D01*
X75667Y212500D01*
X75540Y211833D01*
X75223Y211333D01*
X74653Y211083D01*
X73133D01*
G01X78360Y208833D02*
X80640Y214000D01*
G01X83143Y209000D02*
Y214000D01*
X86057Y209000D01*
Y214000D01*
G01X89700Y208833D02*
X89573Y208917D01*
Y209083D01*
X89700Y209167D01*
X89827Y209083D01*
Y208917D01*
X89700Y208833D01*
G01Y211083D02*
X89573Y211167D01*
Y211333D01*
X89700Y211417D01*
X89827Y211333D01*
Y211167D01*
X89700Y211083D01*
G01X93407Y209000D02*
Y214000D01*
X94673D01*
X95180Y213750D01*
X95560Y213417D01*
X95877Y212917D01*
X96130Y212333D01*
X96193Y211500D01*
X96130Y210667D01*
X95877Y210083D01*
X95560Y209583D01*
X95180Y209250D01*
X94673Y209000D01*
X93407D01*
G01X98317D02*
X99900Y214000D01*
X101483Y209000D01*
G01X100913Y210750D02*
X98887D01*
G01X105000Y214000D02*
X104493Y213833D01*
X104113Y213417D01*
X103860Y212917D01*
X103670Y212250D01*
X103607Y211500D01*
X103670Y210750D01*
X103860Y210083D01*
X104113Y209583D01*
X104493Y209167D01*
X105000Y209000D01*
X105507Y209167D01*
X105887Y209583D01*
X106140Y210083D01*
X106330Y210750D01*
X106393Y211500D01*
X106330Y212250D01*
X106140Y212917D01*
X105887Y213417D01*
X105507Y213833D01*
X105000Y214000D01*
G01X108897Y209000D02*
Y214000D01*
X111303D01*
G01X110417Y211583D02*
X108897D01*
G01X115200Y214000D02*
X114693Y213833D01*
X114313Y213417D01*
X114060Y212917D01*
X113870Y212250D01*
X113807Y211500D01*
X113870Y210750D01*
X114060Y210083D01*
X114313Y209583D01*
X114693Y209167D01*
X115200Y209000D01*
X115707Y209167D01*
X116087Y209583D01*
X116340Y210083D01*
X116530Y210750D01*
X116593Y211500D01*
X116530Y212250D01*
X116340Y212917D01*
X116087Y213417D01*
X115707Y213833D01*
X115200Y214000D01*
G01X120300D02*
Y209000D01*
G01X118843Y214000D02*
X121757D01*
G01X125400Y209000D02*
Y211250D01*
X124133Y214000D01*
G01X126667D02*
X125400Y211250D01*
G01X131007Y211667D02*
X131260Y211917D01*
X131450Y212333D01*
X131577Y212917D01*
X131450Y213417D01*
X131197Y213750D01*
X130753Y214000D01*
X129043D01*
Y209000D01*
X131133D01*
X131577Y209333D01*
X131830Y209833D01*
X131957Y210417D01*
X131830Y211000D01*
X131450Y211500D01*
X131007Y211667D01*
X129043D01*
G01X136360Y209000D02*
Y214000D01*
X134017Y210417D01*
X137183D01*
G01X139307Y209000D02*
Y214000D01*
X140573D01*
X141080Y213750D01*
X141460Y213417D01*
X141777Y212917D01*
X142030Y212333D01*
X142093Y211500D01*
X142030Y210667D01*
X141777Y210083D01*
X141460Y209583D01*
X141080Y209250D01*
X140573Y209000D01*
X139307D01*
G01X145800Y214000D02*
X145293Y213833D01*
X144913Y213417D01*
X144660Y212917D01*
X144470Y212250D01*
X144407Y211500D01*
X144470Y210750D01*
X144660Y210083D01*
X144913Y209583D01*
X145293Y209167D01*
X145800Y209000D01*
X146307Y209167D01*
X146687Y209583D01*
X146940Y210083D01*
X147130Y210750D01*
X147193Y211500D01*
X147130Y212250D01*
X146940Y212917D01*
X146687Y213417D01*
X146307Y213833D01*
X145800Y214000D01*
G01X73133Y202000D02*
Y207000D01*
X74717D01*
X75223Y206750D01*
X75540Y206417D01*
X75667Y205750D01*
X75540Y205083D01*
X75160Y204667D01*
X74717Y204417D01*
X73133D01*
G01X74717D02*
X75667Y202000D01*
G01X78550Y204250D02*
X80577D01*
X80387Y204833D01*
X80070Y205167D01*
X79627Y205333D01*
X79183Y205250D01*
X78803Y205000D01*
X78550Y204417D01*
X78423Y203917D01*
Y203417D01*
X78550Y202917D01*
X78867Y202417D01*
X79247Y202083D01*
X79690Y202000D01*
X80133Y202167D01*
X80577Y202667D01*
G01X83460Y205333D02*
X84600Y202000D01*
X85740Y205333D01*
G01X89700Y201833D02*
X89573Y201917D01*
Y202083D01*
X89700Y202167D01*
X89827Y202083D01*
Y201917D01*
X89700Y201833D01*
G01Y204083D02*
X89573Y204167D01*
Y204333D01*
X89700Y204417D01*
X89827Y204333D01*
Y204167D01*
X89700Y204083D01*
G01X93407Y202000D02*
Y207000D01*
X94673D01*
X95180Y206750D01*
X95560Y206417D01*
X95877Y205917D01*
X96130Y205333D01*
X96193Y204500D01*
X96130Y203667D01*
X95877Y203083D01*
X95560Y202583D01*
X95180Y202250D01*
X94673Y202000D01*
X93407D01*
G01X69400Y221100D02*
X75600D01*
Y217900D01*
X69400D01*
Y221100D01*
G01X63243Y204342D02*
X63013Y204497D01*
X62745Y204600D01*
X62438D01*
X62093Y204445D01*
X61825Y204187D01*
X61633Y203877D01*
X61480Y203360D01*
X61442Y202895D01*
X61518Y202430D01*
X61633Y202120D01*
X61863Y201810D01*
X62132Y201603D01*
X62400Y201500D01*
X62668D01*
X62937Y201603D01*
X63167Y201758D01*
X63358Y201965D01*
G01X65500Y201500D02*
Y204600D01*
X65040Y203980D01*
G01Y201500D02*
X65960D01*
G01X68600D02*
Y204600D01*
X68140Y203980D01*
G01Y201500D02*
X69060D01*
G01X69400Y229100D02*
X75600D01*
Y225900D01*
X69400D01*
Y229100D01*
G01Y233100D02*
X75600D01*
Y229900D01*
X69400D01*
Y233100D01*
G01X75600Y237900D02*
X69400D01*
Y241100D01*
X75600D01*
Y237900D01*
G01Y233900D02*
X69400D01*
Y237100D01*
X75600D01*
Y233900D01*
G01X69400Y225100D02*
X75600D01*
Y221900D01*
X69400D01*
Y225100D01*
G01X73293Y245342D02*
X73063Y245497D01*
X72795Y245600D01*
X72488D01*
X72143Y245445D01*
X71875Y245187D01*
X71683Y244877D01*
X71530Y244360D01*
X71492Y243895D01*
X71568Y243430D01*
X71683Y243120D01*
X71913Y242810D01*
X72182Y242603D01*
X72450Y242500D01*
X72718D01*
X72987Y242603D01*
X73217Y242758D01*
X73408Y242965D01*
G01X74707D02*
X74937Y242707D01*
X75205Y242552D01*
X75550Y242500D01*
X75895Y242603D01*
X76163Y242810D01*
X76355Y243172D01*
X76393Y243585D01*
X76317Y243998D01*
X76125Y244257D01*
X75857Y244463D01*
X75588Y244515D01*
X75320Y244463D01*
X74975Y244257D01*
X75090Y245600D01*
X76125D01*
G01X75293Y256842D02*
X75063Y256997D01*
X74795Y257100D01*
X74488D01*
X74143Y256945D01*
X73875Y256687D01*
X73683Y256377D01*
X73530Y255860D01*
X73492Y255395D01*
X73568Y254930D01*
X73683Y254620D01*
X73913Y254310D01*
X74182Y254103D01*
X74450Y254000D01*
X74718D01*
X74987Y254103D01*
X75217Y254258D01*
X75408Y254465D01*
G01X77550Y254000D02*
Y257100D01*
X77090Y256480D01*
G01Y254000D02*
X78010D01*
G01X68400Y263300D02*
X78600D01*
Y258700D01*
X68400D01*
Y263300D01*
G01X70000Y248633D02*
X66900D01*
Y249592D01*
X67055Y249898D01*
X67262Y250090D01*
X67675Y250167D01*
X68088Y250090D01*
X68347Y249860D01*
X68502Y249592D01*
Y248633D01*
G01Y249592D02*
X70000Y250167D01*
G01X68708Y251772D02*
X68347Y252040D01*
X68140Y252270D01*
X68037Y252577D01*
X68140Y252845D01*
X68347Y253037D01*
X68657Y253190D01*
X69018Y253228D01*
X69328Y253190D01*
X69638Y253037D01*
X69897Y252807D01*
X70000Y252538D01*
X69897Y252232D01*
X69587Y251963D01*
X69122Y251810D01*
X68605Y251772D01*
X67933Y251848D01*
X67572Y251963D01*
X67210Y252155D01*
X66952Y252423D01*
X66900Y252692D01*
X67003Y252960D01*
X67262Y253152D01*
G01X69535Y254757D02*
X69793Y254987D01*
X69948Y255255D01*
X70000Y255600D01*
X69897Y255945D01*
X69690Y256213D01*
X69328Y256405D01*
X68915Y256443D01*
X68502Y256367D01*
X68243Y256175D01*
X68037Y255907D01*
X67985Y255638D01*
X68037Y255370D01*
X68243Y255025D01*
X66900Y255140D01*
Y256175D01*
G01X75900Y246400D02*
Y252600D01*
X79100D01*
Y246400D01*
X75900D01*
G01X64600Y263900D02*
X58400D01*
Y267100D01*
X64600D01*
Y263900D01*
G01X78293Y267342D02*
X78063Y267497D01*
X77795Y267600D01*
X77488D01*
X77143Y267445D01*
X76875Y267187D01*
X76683Y266877D01*
X76530Y266360D01*
X76492Y265895D01*
X76568Y265430D01*
X76683Y265120D01*
X76913Y264810D01*
X77182Y264603D01*
X77450Y264500D01*
X77718D01*
X77987Y264603D01*
X78217Y264758D01*
X78408Y264965D01*
G01X79822Y267083D02*
X80052Y267393D01*
X80320Y267548D01*
X80627Y267600D01*
X81010Y267497D01*
X81278Y267238D01*
X81355Y266928D01*
X81317Y266618D01*
X81163Y266360D01*
X80397Y265843D01*
X80052Y265482D01*
X79822Y264965D01*
X79745Y264500D01*
X81355D01*
G01X68900Y267100D02*
X75100D01*
Y263900D01*
X68900D01*
Y267100D01*
G01X64400Y246100D02*
X70600D01*
Y242900D01*
X64400D01*
Y246100D01*
G01X63514Y273032D02*
X61024D01*
Y292262D01*
G01Y297122D02*
Y312402D01*
G01Y317522D02*
Y324212D01*
G01X111024Y329332D02*
Y335236D01*
X61024D01*
Y329332D01*
G01X95532Y-320235D02*
Y-312235D01*
X100132Y-320235D01*
Y-312235D01*
G01X105832Y-314902D02*
Y-320235D01*
G01Y-312768D02*
X105632Y-312635D01*
Y-312368D01*
X105832Y-312235D01*
X106032Y-312368D01*
Y-312635D01*
X105832Y-312768D01*
G01X112132Y-320235D02*
Y-314902D01*
G01Y-316235D02*
X112532Y-315568D01*
X113132Y-315035D01*
X113932Y-314902D01*
X114632Y-315035D01*
X115232Y-315568D01*
X115532Y-316502D01*
Y-320235D01*
G01X123632D02*
Y-314902D01*
G01Y-315835D02*
X123232Y-315302D01*
X122632Y-315035D01*
X121932Y-314902D01*
X121232Y-315168D01*
X120632Y-315702D01*
X120232Y-316502D01*
X120032Y-317568D01*
X120232Y-318635D01*
X120632Y-319435D01*
X121232Y-319968D01*
X121932Y-320235D01*
X122632Y-320102D01*
X123232Y-319702D01*
X123632Y-319169D01*
G01X88232Y-294169D02*
X89032Y-294835D01*
X89932Y-295235D01*
X90732D01*
X91532Y-294835D01*
X92132Y-294169D01*
X92432Y-293235D01*
X92232Y-292302D01*
X91732Y-291502D01*
X90832Y-290968D01*
X89632Y-290702D01*
X88932Y-290168D01*
X88632Y-289235D01*
X88832Y-288302D01*
X89332Y-287635D01*
X90032Y-287235D01*
X90732D01*
X91432Y-287502D01*
X92032Y-288168D01*
G01X97132Y-287235D02*
X99532D01*
G01X98332D02*
Y-295235D01*
G01X97132D02*
X99532D01*
G01X104332Y-287235D02*
Y-295235D01*
X108332D01*
G01X112132D02*
Y-287235D01*
G01X115932D02*
X112132Y-292169D01*
G01X116532Y-295235D02*
X113832Y-289902D01*
G01X121032Y-292568D02*
X123632D01*
G01X130332Y-287235D02*
Y-295235D01*
G01X128032Y-287235D02*
X132632D01*
G01X138332Y-295235D02*
X137532Y-295102D01*
X136832Y-294568D01*
X136232Y-293768D01*
X135832Y-292835D01*
X135632Y-291768D01*
Y-290702D01*
X135832Y-289635D01*
X136232Y-288702D01*
X136832Y-287902D01*
X137532Y-287368D01*
X138332Y-287235D01*
X139132Y-287368D01*
X139832Y-287902D01*
X140432Y-288702D01*
X140832Y-289635D01*
X141032Y-290702D01*
Y-291768D01*
X140832Y-292835D01*
X140432Y-293768D01*
X139832Y-294568D01*
X139132Y-295102D01*
X138332Y-295235D01*
G01X144332D02*
Y-287235D01*
X146732D01*
X147532Y-287635D01*
X148132Y-288568D01*
X148332Y-289635D01*
X148132Y-290702D01*
X147632Y-291502D01*
X146732Y-291902D01*
X144332D01*
G01X84410Y-4724D02*
Y96654D01*
X112441D01*
Y-4724D01*
X84410D01*
G01Y-2559D02*
X112441D01*
G01Y-4724D02*
X113032D01*
Y98622D01*
X83819D01*
Y-4724D01*
X84410D01*
G01X83000Y32383D02*
X79900D01*
Y33342D01*
X80055Y33648D01*
X80262Y33840D01*
X80675Y33917D01*
X81088Y33840D01*
X81347Y33610D01*
X81502Y33342D01*
Y32383D01*
G01Y33342D02*
X83000Y33917D01*
G01X82380Y35407D02*
X82742Y35637D01*
X82948Y35943D01*
X83000Y36288D01*
X82948Y36595D01*
X82690Y36902D01*
X82380Y37093D01*
X82070Y37132D01*
X81708Y37055D01*
X81450Y36787D01*
X81347Y36518D01*
Y36173D01*
G01Y36518D02*
X81192Y36748D01*
X80933Y36940D01*
X80623Y37017D01*
X80313Y36940D01*
X80055Y36748D01*
X79900Y36403D01*
X79952Y36058D01*
X80158Y35713D01*
G01X80400Y78807D02*
X82622D01*
X83087Y78960D01*
X83397Y79267D01*
X83500Y79650D01*
X83397Y80033D01*
X83087Y80340D01*
X82622Y80493D01*
X80400D01*
G01X83500Y82750D02*
X80400D01*
X81020Y82290D01*
G01X83500D02*
Y83210D01*
G01Y85850D02*
X80400D01*
X81020Y85390D01*
G01X83500D02*
Y86310D01*
G01X84900Y107807D02*
X87122D01*
X87587Y107960D01*
X87897Y108267D01*
X88000Y108650D01*
X87897Y109033D01*
X87587Y109340D01*
X87122Y109493D01*
X84900D01*
G01X88000Y111750D02*
X84900D01*
X85520Y111290D01*
G01X88000D02*
Y112210D01*
G01X84900Y114850D02*
X85003Y114543D01*
X85262Y114313D01*
X85572Y114160D01*
X85985Y114045D01*
X86450Y114007D01*
X86915Y114045D01*
X87328Y114160D01*
X87638Y114313D01*
X87897Y114543D01*
X88000Y114850D01*
X87897Y115157D01*
X87638Y115387D01*
X87328Y115540D01*
X86915Y115655D01*
X86450Y115693D01*
X85985Y115655D01*
X85572Y115540D01*
X85262Y115387D01*
X85003Y115157D01*
X84900Y114850D01*
G01X96537Y104594D02*
X92463D01*
Y116406D01*
X96537D01*
Y104594D01*
G01X83865Y101028D02*
X84057Y100718D01*
X84287Y100511D01*
X84555Y100408D01*
X84862Y100511D01*
X85092Y100718D01*
X85322Y101028D01*
X85399Y101441D01*
Y103508D01*
G01X87004Y102991D02*
X87234Y103301D01*
X87502Y103456D01*
X87809Y103508D01*
X88192Y103405D01*
X88460Y103146D01*
X88537Y102836D01*
X88499Y102526D01*
X88345Y102268D01*
X87579Y101751D01*
X87234Y101390D01*
X87004Y100873D01*
X86927Y100408D01*
X88537D01*
G01X90133Y122500D02*
Y125600D01*
X91092D01*
X91398Y125445D01*
X91590Y125238D01*
X91667Y124825D01*
X91590Y124412D01*
X91360Y124153D01*
X91092Y123998D01*
X90133D01*
G01X91092D02*
X91667Y122500D01*
G01X93272Y123792D02*
X93540Y124153D01*
X93770Y124360D01*
X94077Y124463D01*
X94345Y124360D01*
X94537Y124153D01*
X94690Y123843D01*
X94728Y123482D01*
X94690Y123172D01*
X94537Y122862D01*
X94307Y122603D01*
X94038Y122500D01*
X93732Y122603D01*
X93463Y122913D01*
X93310Y123378D01*
X93272Y123895D01*
X93348Y124567D01*
X93463Y124928D01*
X93655Y125290D01*
X93923Y125548D01*
X94192Y125600D01*
X94460Y125497D01*
X94652Y125238D01*
G01X96372Y123792D02*
X96640Y124153D01*
X96870Y124360D01*
X97177Y124463D01*
X97445Y124360D01*
X97637Y124153D01*
X97790Y123843D01*
X97828Y123482D01*
X97790Y123172D01*
X97637Y122862D01*
X97407Y122603D01*
X97138Y122500D01*
X96832Y122603D01*
X96563Y122913D01*
X96410Y123378D01*
X96372Y123895D01*
X96448Y124567D01*
X96563Y124928D01*
X96755Y125290D01*
X97023Y125548D01*
X97292Y125600D01*
X97560Y125497D01*
X97752Y125238D01*
G01X89400Y121600D02*
X95600D01*
Y118400D01*
X89400D01*
Y121600D01*
G01X83633Y222000D02*
Y225100D01*
X84592D01*
X84898Y224945D01*
X85090Y224738D01*
X85167Y224325D01*
X85090Y223912D01*
X84860Y223653D01*
X84592Y223498D01*
X83633D01*
G01X84592D02*
X85167Y222000D01*
G01X87500D02*
Y225100D01*
X87040Y224480D01*
G01Y222000D02*
X87960D01*
G01X89757Y222465D02*
X89987Y222207D01*
X90255Y222052D01*
X90600Y222000D01*
X90945Y222103D01*
X91213Y222310D01*
X91405Y222672D01*
X91443Y223085D01*
X91367Y223498D01*
X91175Y223757D01*
X90907Y223963D01*
X90638Y224015D01*
X90370Y223963D01*
X90025Y223757D01*
X90140Y225100D01*
X91175D01*
G01X83633Y218000D02*
Y221100D01*
X84592D01*
X84898Y220945D01*
X85090Y220738D01*
X85167Y220325D01*
X85090Y219912D01*
X84860Y219653D01*
X84592Y219498D01*
X83633D01*
G01X84592D02*
X85167Y218000D01*
G01X87500D02*
Y221100D01*
X87040Y220480D01*
G01Y218000D02*
X87960D01*
G01X91060D02*
Y221100D01*
X89642Y218878D01*
X91558D01*
G01X160630Y247543D02*
G03X98967Y238490I-31496J0D01*
G01X83633Y226000D02*
Y229100D01*
X84592D01*
X84898Y228945D01*
X85090Y228738D01*
X85167Y228325D01*
X85090Y227912D01*
X84860Y227653D01*
X84592Y227498D01*
X83633D01*
G01X84592D02*
X85167Y226000D01*
G01X86772Y228583D02*
X87002Y228893D01*
X87270Y229048D01*
X87577Y229100D01*
X87960Y228997D01*
X88228Y228738D01*
X88305Y228428D01*
X88267Y228118D01*
X88113Y227860D01*
X87347Y227343D01*
X87002Y226982D01*
X86772Y226465D01*
X86695Y226000D01*
X88305D01*
G01X89757Y226465D02*
X89987Y226207D01*
X90255Y226052D01*
X90600Y226000D01*
X90945Y226103D01*
X91213Y226310D01*
X91405Y226672D01*
X91443Y227085D01*
X91367Y227498D01*
X91175Y227757D01*
X90907Y227963D01*
X90638Y228015D01*
X90370Y227963D01*
X90025Y227757D01*
X90140Y229100D01*
X91175D01*
G01X83633Y230000D02*
Y233100D01*
X84592D01*
X84898Y232945D01*
X85090Y232738D01*
X85167Y232325D01*
X85090Y231912D01*
X84860Y231653D01*
X84592Y231498D01*
X83633D01*
G01X84592D02*
X85167Y230000D01*
G01X86772Y232583D02*
X87002Y232893D01*
X87270Y233048D01*
X87577Y233100D01*
X87960Y232997D01*
X88228Y232738D01*
X88305Y232428D01*
X88267Y232118D01*
X88113Y231860D01*
X87347Y231343D01*
X87002Y230982D01*
X86772Y230465D01*
X86695Y230000D01*
X88305D01*
G01X90600Y233100D02*
X90293Y232997D01*
X90063Y232738D01*
X89910Y232428D01*
X89795Y232015D01*
X89757Y231550D01*
X89795Y231085D01*
X89910Y230672D01*
X90063Y230362D01*
X90293Y230103D01*
X90600Y230000D01*
X90907Y230103D01*
X91137Y230362D01*
X91290Y230672D01*
X91405Y231085D01*
X91443Y231550D01*
X91405Y232015D01*
X91290Y232428D01*
X91137Y232738D01*
X90907Y232997D01*
X90600Y233100D01*
G01X83633Y238000D02*
Y241100D01*
X84592D01*
X84898Y240945D01*
X85090Y240738D01*
X85167Y240325D01*
X85090Y239912D01*
X84860Y239653D01*
X84592Y239498D01*
X83633D01*
G01X84592D02*
X85167Y238000D01*
G01X87500D02*
Y241100D01*
X87040Y240480D01*
G01Y238000D02*
X87960D01*
G01X90523D02*
X90600Y238672D01*
X90715Y239240D01*
X90868Y239757D01*
X91060Y240325D01*
X91367Y241100D01*
X89833D01*
G01X83633Y234000D02*
Y237100D01*
X84592D01*
X84898Y236945D01*
X85090Y236738D01*
X85167Y236325D01*
X85090Y235912D01*
X84860Y235653D01*
X84592Y235498D01*
X83633D01*
G01X84592D02*
X85167Y234000D01*
G01X87500D02*
Y237100D01*
X87040Y236480D01*
G01Y234000D02*
X87960D01*
G01X89872Y235292D02*
X90140Y235653D01*
X90370Y235860D01*
X90677Y235963D01*
X90945Y235860D01*
X91137Y235653D01*
X91290Y235343D01*
X91328Y234982D01*
X91290Y234672D01*
X91137Y234362D01*
X90907Y234103D01*
X90638Y234000D01*
X90332Y234103D01*
X90063Y234413D01*
X89910Y234878D01*
X89872Y235395D01*
X89948Y236067D01*
X90063Y236428D01*
X90255Y236790D01*
X90523Y237048D01*
X90792Y237100D01*
X91060Y236997D01*
X91252Y236738D01*
G01X91500Y246633D02*
X88400D01*
Y247592D01*
X88555Y247898D01*
X88762Y248090D01*
X89175Y248167D01*
X89588Y248090D01*
X89847Y247860D01*
X90002Y247592D01*
Y246633D01*
G01Y247592D02*
X91500Y248167D01*
G01X90208Y249772D02*
X89847Y250040D01*
X89640Y250270D01*
X89537Y250577D01*
X89640Y250845D01*
X89847Y251037D01*
X90157Y251190D01*
X90518Y251228D01*
X90828Y251190D01*
X91138Y251037D01*
X91397Y250807D01*
X91500Y250538D01*
X91397Y250232D01*
X91087Y249963D01*
X90622Y249810D01*
X90105Y249772D01*
X89433Y249848D01*
X89072Y249963D01*
X88710Y250155D01*
X88452Y250423D01*
X88400Y250692D01*
X88503Y250960D01*
X88762Y251152D01*
G01X91500Y253600D02*
X91448Y253868D01*
X91293Y254175D01*
X91035Y254367D01*
X90673Y254443D01*
X90312Y254367D01*
X90002Y254137D01*
X89847Y253792D01*
Y253408D01*
X89743Y253178D01*
X89485Y252987D01*
X89123Y252910D01*
X88762Y253025D01*
X88503Y253293D01*
X88400Y253600D01*
X88503Y253907D01*
X88762Y254175D01*
X89123Y254290D01*
X89485Y254213D01*
X89743Y254022D01*
X89847Y253792D01*
Y253408D01*
X90002Y253063D01*
X90312Y252833D01*
X90673Y252757D01*
X91035Y252833D01*
X91293Y253025D01*
X91448Y253332D01*
X91500Y253600D01*
G01X83100Y252600D02*
Y246400D01*
X79900D01*
Y252600D01*
X83100D01*
G01X96000Y246633D02*
X92900D01*
Y247592D01*
X93055Y247898D01*
X93262Y248090D01*
X93675Y248167D01*
X94088Y248090D01*
X94347Y247860D01*
X94502Y247592D01*
Y246633D01*
G01Y247592D02*
X96000Y248167D01*
G01X94708Y249772D02*
X94347Y250040D01*
X94140Y250270D01*
X94037Y250577D01*
X94140Y250845D01*
X94347Y251037D01*
X94657Y251190D01*
X95018Y251228D01*
X95328Y251190D01*
X95638Y251037D01*
X95897Y250807D01*
X96000Y250538D01*
X95897Y250232D01*
X95587Y249963D01*
X95122Y249810D01*
X94605Y249772D01*
X93933Y249848D01*
X93572Y249963D01*
X93210Y250155D01*
X92952Y250423D01*
X92900Y250692D01*
X93003Y250960D01*
X93262Y251152D01*
G01X96000Y253523D02*
X95328Y253600D01*
X94760Y253715D01*
X94243Y253868D01*
X93675Y254060D01*
X92900Y254367D01*
Y252833D01*
G01X87100Y252600D02*
Y246400D01*
X83900D01*
Y252600D01*
X87100D01*
G01X114307Y9100D02*
Y6878D01*
X114460Y6413D01*
X114767Y6103D01*
X115150Y6000D01*
X115533Y6103D01*
X115840Y6413D01*
X115993Y6878D01*
Y9100D01*
G01X117522Y7292D02*
X117790Y7653D01*
X118020Y7860D01*
X118327Y7963D01*
X118595Y7860D01*
X118787Y7653D01*
X118940Y7343D01*
X118978Y6982D01*
X118940Y6672D01*
X118787Y6362D01*
X118557Y6103D01*
X118288Y6000D01*
X117982Y6103D01*
X117713Y6413D01*
X117560Y6878D01*
X117522Y7395D01*
X117598Y8067D01*
X117713Y8428D01*
X117905Y8790D01*
X118173Y9048D01*
X118442Y9100D01*
X118710Y8997D01*
X118902Y8738D01*
G01X133416Y18216D02*
X127573Y24059D01*
X119842D01*
Y4373D01*
X146990D01*
Y24059D01*
X139259D01*
X133416Y18216D01*
G01X125438Y25611D02*
X119238D01*
Y28811D01*
X125438D01*
Y25611D01*
G01X118793Y32842D02*
X118563Y32997D01*
X118295Y33100D01*
X117988D01*
X117643Y32945D01*
X117375Y32687D01*
X117183Y32377D01*
X117030Y31860D01*
X116992Y31395D01*
X117068Y30930D01*
X117183Y30620D01*
X117413Y30310D01*
X117682Y30103D01*
X117950Y30000D01*
X118218D01*
X118487Y30103D01*
X118717Y30258D01*
X118908Y30465D01*
G01X120973Y30000D02*
X121050Y30672D01*
X121165Y31240D01*
X121318Y31757D01*
X121510Y32325D01*
X121817Y33100D01*
X120283D01*
G01X119973Y43425D02*
Y57205D01*
G01X152469Y43425D02*
G02X119973I-16248J0D01*
G01Y57205D02*
G02X152469I16248J0D01*
G01X116383Y88600D02*
Y85500D01*
X117917D01*
G01X120250D02*
Y88600D01*
X119790Y87980D01*
G01Y85500D02*
X120710D01*
G01X127848Y99921D02*
Y87921D01*
X121048D01*
Y99921D01*
X127848D01*
G01X114930Y80922D02*
Y78700D01*
X115083Y78235D01*
X115390Y77925D01*
X115773Y77822D01*
X116156Y77925D01*
X116463Y78235D01*
X116616Y78700D01*
Y80922D01*
G01X118873Y77822D02*
X119141Y77874D01*
X119448Y78029D01*
X119640Y78287D01*
X119716Y78649D01*
X119640Y79010D01*
X119410Y79320D01*
X119065Y79475D01*
X118681D01*
X118451Y79579D01*
X118260Y79837D01*
X118183Y80199D01*
X118298Y80560D01*
X118566Y80819D01*
X118873Y80922D01*
X119180Y80819D01*
X119448Y80560D01*
X119563Y80199D01*
X119486Y79837D01*
X119295Y79579D01*
X119065Y79475D01*
X118681D01*
X118336Y79320D01*
X118106Y79010D01*
X118030Y78649D01*
X118106Y78287D01*
X118298Y78029D01*
X118605Y77874D01*
X118873Y77822D01*
G01X120000Y90383D02*
X116900D01*
Y91342D01*
X117055Y91648D01*
X117262Y91840D01*
X117675Y91917D01*
X118088Y91840D01*
X118347Y91610D01*
X118502Y91342D01*
Y90383D01*
G01Y91342D02*
X120000Y91917D01*
G01X119535Y93407D02*
X119793Y93637D01*
X119948Y93905D01*
X120000Y94250D01*
X119897Y94595D01*
X119690Y94863D01*
X119328Y95055D01*
X118915Y95093D01*
X118502Y95017D01*
X118243Y94825D01*
X118037Y94557D01*
X117985Y94288D01*
X118037Y94020D01*
X118243Y93675D01*
X116900Y93790D01*
Y94825D01*
G01X120000Y97350D02*
X116900D01*
X117520Y96890D01*
G01X120000D02*
Y97810D01*
G01X124375Y96792D02*
Y90592D01*
X121175D01*
Y96792D01*
X124375D01*
G01X113307Y118100D02*
Y115878D01*
X113460Y115413D01*
X113767Y115103D01*
X114150Y115000D01*
X114533Y115103D01*
X114840Y115413D01*
X114993Y115878D01*
Y118100D01*
G01X117173Y115000D02*
X117250Y115672D01*
X117365Y116240D01*
X117518Y116757D01*
X117710Y117325D01*
X118017Y118100D01*
X116483D01*
G01X126000Y120100D02*
X123498Y122602D01*
X119154D01*
Y110398D01*
X132846D01*
Y122602D01*
X128502D01*
X126000Y120100D01*
G01X109633Y104000D02*
Y107100D01*
X110592D01*
X110898Y106945D01*
X111090Y106738D01*
X111167Y106325D01*
X111090Y105912D01*
X110860Y105653D01*
X110592Y105498D01*
X109633D01*
G01X110592D02*
X111167Y104000D01*
G01X113960D02*
Y107100D01*
X112542Y104878D01*
X114458D01*
G01X115872Y106583D02*
X116102Y106893D01*
X116370Y107048D01*
X116677Y107100D01*
X117060Y106997D01*
X117328Y106738D01*
X117405Y106428D01*
X117367Y106118D01*
X117213Y105860D01*
X116447Y105343D01*
X116102Y104982D01*
X115872Y104465D01*
X115795Y104000D01*
X117405D01*
G01X109633Y108000D02*
Y111100D01*
X110592D01*
X110898Y110945D01*
X111090Y110738D01*
X111167Y110325D01*
X111090Y109912D01*
X110860Y109653D01*
X110592Y109498D01*
X109633D01*
G01X110592D02*
X111167Y108000D01*
G01X113960D02*
Y111100D01*
X112542Y108878D01*
X114458D01*
G01X116600Y108000D02*
Y111100D01*
X116140Y110480D01*
G01Y108000D02*
X117060D01*
G01X109633Y100000D02*
Y103100D01*
X110592D01*
X110898Y102945D01*
X111090Y102738D01*
X111167Y102325D01*
X111090Y101912D01*
X110860Y101653D01*
X110592Y101498D01*
X109633D01*
G01X110592D02*
X111167Y100000D01*
G01X113960D02*
Y103100D01*
X112542Y100878D01*
X114458D01*
G01X116600Y103100D02*
X116293Y102997D01*
X116063Y102738D01*
X115910Y102428D01*
X115795Y102015D01*
X115757Y101550D01*
X115795Y101085D01*
X115910Y100672D01*
X116063Y100362D01*
X116293Y100103D01*
X116600Y100000D01*
X116907Y100103D01*
X117137Y100362D01*
X117290Y100672D01*
X117405Y101085D01*
X117443Y101550D01*
X117405Y102015D01*
X117290Y102428D01*
X117137Y102738D01*
X116907Y102997D01*
X116600Y103100D01*
G01X109293Y127342D02*
X109063Y127497D01*
X108795Y127600D01*
X108488D01*
X108143Y127445D01*
X107875Y127187D01*
X107683Y126877D01*
X107530Y126360D01*
X107492Y125895D01*
X107568Y125430D01*
X107683Y125120D01*
X107913Y124810D01*
X108182Y124603D01*
X108450Y124500D01*
X108718D01*
X108987Y124603D01*
X109217Y124758D01*
X109408Y124965D01*
G01X111550Y124500D02*
X111818Y124552D01*
X112125Y124707D01*
X112317Y124965D01*
X112393Y125327D01*
X112317Y125688D01*
X112087Y125998D01*
X111742Y126153D01*
X111358D01*
X111128Y126257D01*
X110937Y126515D01*
X110860Y126877D01*
X110975Y127238D01*
X111243Y127497D01*
X111550Y127600D01*
X111857Y127497D01*
X112125Y127238D01*
X112240Y126877D01*
X112163Y126515D01*
X111972Y126257D01*
X111742Y126153D01*
X111358D01*
X111013Y125998D01*
X110783Y125688D01*
X110707Y125327D01*
X110783Y124965D01*
X110975Y124707D01*
X111282Y124552D01*
X111550Y124500D01*
G01X113400Y127600D02*
X119600D01*
Y124400D01*
X113400D01*
Y127600D01*
G01X106243Y131342D02*
X106013Y131497D01*
X105745Y131600D01*
X105438D01*
X105093Y131445D01*
X104825Y131187D01*
X104633Y130877D01*
X104480Y130360D01*
X104442Y129895D01*
X104518Y129430D01*
X104633Y129120D01*
X104863Y128810D01*
X105132Y128603D01*
X105400Y128500D01*
X105668D01*
X105937Y128603D01*
X106167Y128758D01*
X106358Y128965D01*
G01X108500Y128500D02*
Y131600D01*
X108040Y130980D01*
G01Y128500D02*
X108960D01*
G01X110757Y129120D02*
X110987Y128758D01*
X111293Y128552D01*
X111638Y128500D01*
X111945Y128552D01*
X112252Y128810D01*
X112443Y129120D01*
X112482Y129430D01*
X112405Y129792D01*
X112137Y130050D01*
X111868Y130153D01*
X111523D01*
G01X111868D02*
X112098Y130308D01*
X112290Y130567D01*
X112367Y130877D01*
X112290Y131187D01*
X112098Y131445D01*
X111753Y131600D01*
X111408Y131548D01*
X111063Y131342D01*
G01X113400Y131600D02*
X119600D01*
Y128400D01*
X113400D01*
Y131600D01*
G01X121500Y131500D02*
Y137500D01*
X133500D01*
Y131500D01*
X121500D01*
G01Y124500D02*
Y130500D01*
X133500D01*
Y124500D01*
X121500D01*
G01X111024Y292262D02*
Y273032D01*
X108534D01*
G01X118000Y286500D02*
Y280500D01*
G01D02*
X124000D01*
G01X111024Y312402D02*
Y297112D01*
G01X122162Y290194D02*
X122909Y289569D01*
X123749Y289194D01*
X124495D01*
X125242Y289569D01*
X125802Y290194D01*
X126082Y291069D01*
X125895Y291944D01*
X125429Y292694D01*
X124589Y293194D01*
X123469Y293444D01*
X122815Y293944D01*
X122535Y294819D01*
X122722Y295694D01*
X123189Y296319D01*
X123842Y296694D01*
X124495D01*
X125149Y296444D01*
X125709Y295819D01*
G01X129942Y288944D02*
X133302Y296694D01*
G01X136975Y289194D02*
Y296694D01*
X141269Y289194D01*
Y296694D01*
G01X118000Y308059D02*
Y302059D01*
G01X111024Y324212D02*
Y317522D01*
G01X124000Y308059D02*
X118000D01*
G01X126485Y73478D02*
X122411D01*
Y85290D01*
X126485D01*
Y73478D01*
G01X132633Y86500D02*
Y89600D01*
X133592D01*
X133898Y89445D01*
X134090Y89238D01*
X134167Y88825D01*
X134090Y88412D01*
X133860Y88153D01*
X133592Y87998D01*
X132633D01*
G01X133592D02*
X134167Y86500D01*
G01X135657Y87120D02*
X135887Y86758D01*
X136193Y86552D01*
X136538Y86500D01*
X136845Y86552D01*
X137152Y86810D01*
X137343Y87120D01*
X137382Y87430D01*
X137305Y87792D01*
X137037Y88050D01*
X136768Y88153D01*
X136423D01*
G01X136768D02*
X136998Y88308D01*
X137190Y88567D01*
X137267Y88877D01*
X137190Y89187D01*
X136998Y89445D01*
X136653Y89600D01*
X136308Y89548D01*
X135963Y89342D01*
G01X139600Y86500D02*
X139868Y86552D01*
X140175Y86707D01*
X140367Y86965D01*
X140443Y87327D01*
X140367Y87688D01*
X140137Y87998D01*
X139792Y88153D01*
X139408D01*
X139178Y88257D01*
X138987Y88515D01*
X138910Y88877D01*
X139025Y89238D01*
X139293Y89497D01*
X139600Y89600D01*
X139907Y89497D01*
X140175Y89238D01*
X140290Y88877D01*
X140213Y88515D01*
X140022Y88257D01*
X139792Y88153D01*
X139408D01*
X139063Y87998D01*
X138833Y87688D01*
X138757Y87327D01*
X138833Y86965D01*
X139025Y86707D01*
X139332Y86552D01*
X139600Y86500D01*
G01X141400Y89600D02*
X147600D01*
Y86400D01*
X141400D01*
Y89600D01*
G01X132633Y78500D02*
Y81600D01*
X133592D01*
X133898Y81445D01*
X134090Y81238D01*
X134167Y80825D01*
X134090Y80412D01*
X133860Y80153D01*
X133592Y79998D01*
X132633D01*
G01X133592D02*
X134167Y78500D01*
G01X135657Y79120D02*
X135887Y78758D01*
X136193Y78552D01*
X136538Y78500D01*
X136845Y78552D01*
X137152Y78810D01*
X137343Y79120D01*
X137382Y79430D01*
X137305Y79792D01*
X137037Y80050D01*
X136768Y80153D01*
X136423D01*
G01X136768D02*
X136998Y80308D01*
X137190Y80567D01*
X137267Y80877D01*
X137190Y81187D01*
X136998Y81445D01*
X136653Y81600D01*
X136308Y81548D01*
X135963Y81342D01*
G01X139523Y78500D02*
X139600Y79172D01*
X139715Y79740D01*
X139868Y80257D01*
X140060Y80825D01*
X140367Y81600D01*
X138833D01*
G01X141400D02*
X147600D01*
Y78400D01*
X141400D01*
Y81600D01*
G01X132633Y90500D02*
Y93600D01*
X133592D01*
X133898Y93445D01*
X134090Y93238D01*
X134167Y92825D01*
X134090Y92412D01*
X133860Y92153D01*
X133592Y91998D01*
X132633D01*
G01X133592D02*
X134167Y90500D01*
G01X135657Y91120D02*
X135887Y90758D01*
X136193Y90552D01*
X136538Y90500D01*
X136845Y90552D01*
X137152Y90810D01*
X137343Y91120D01*
X137382Y91430D01*
X137305Y91792D01*
X137037Y92050D01*
X136768Y92153D01*
X136423D01*
G01X136768D02*
X136998Y92308D01*
X137190Y92567D01*
X137267Y92877D01*
X137190Y93187D01*
X136998Y93445D01*
X136653Y93600D01*
X136308Y93548D01*
X135963Y93342D01*
G01X140060Y90500D02*
Y93600D01*
X138642Y91378D01*
X140558D01*
G01X147600Y90400D02*
X141400D01*
Y93600D01*
X147600D01*
Y90400D01*
G01X132633Y82500D02*
Y85600D01*
X133592D01*
X133898Y85445D01*
X134090Y85238D01*
X134167Y84825D01*
X134090Y84412D01*
X133860Y84153D01*
X133592Y83998D01*
X132633D01*
G01X133592D02*
X134167Y82500D01*
G01X135657Y83120D02*
X135887Y82758D01*
X136193Y82552D01*
X136538Y82500D01*
X136845Y82552D01*
X137152Y82810D01*
X137343Y83120D01*
X137382Y83430D01*
X137305Y83792D01*
X137037Y84050D01*
X136768Y84153D01*
X136423D01*
G01X136768D02*
X136998Y84308D01*
X137190Y84567D01*
X137267Y84877D01*
X137190Y85187D01*
X136998Y85445D01*
X136653Y85600D01*
X136308Y85548D01*
X135963Y85342D01*
G01X138757Y83120D02*
X138987Y82758D01*
X139293Y82552D01*
X139638Y82500D01*
X139945Y82552D01*
X140252Y82810D01*
X140443Y83120D01*
X140482Y83430D01*
X140405Y83792D01*
X140137Y84050D01*
X139868Y84153D01*
X139523D01*
G01X139868D02*
X140098Y84308D01*
X140290Y84567D01*
X140367Y84877D01*
X140290Y85187D01*
X140098Y85445D01*
X139753Y85600D01*
X139408Y85548D01*
X139063Y85342D01*
G01X147600Y82400D02*
X141400D01*
Y85600D01*
X147600D01*
Y82400D01*
G01X132633Y74500D02*
Y77600D01*
X133592D01*
X133898Y77445D01*
X134090Y77238D01*
X134167Y76825D01*
X134090Y76412D01*
X133860Y76153D01*
X133592Y75998D01*
X132633D01*
G01X133592D02*
X134167Y74500D01*
G01X135657Y75120D02*
X135887Y74758D01*
X136193Y74552D01*
X136538Y74500D01*
X136845Y74552D01*
X137152Y74810D01*
X137343Y75120D01*
X137382Y75430D01*
X137305Y75792D01*
X137037Y76050D01*
X136768Y76153D01*
X136423D01*
G01X136768D02*
X136998Y76308D01*
X137190Y76567D01*
X137267Y76877D01*
X137190Y77187D01*
X136998Y77445D01*
X136653Y77600D01*
X136308Y77548D01*
X135963Y77342D01*
G01X138872Y77083D02*
X139102Y77393D01*
X139370Y77548D01*
X139677Y77600D01*
X140060Y77497D01*
X140328Y77238D01*
X140405Y76928D01*
X140367Y76618D01*
X140213Y76360D01*
X139447Y75843D01*
X139102Y75482D01*
X138872Y74965D01*
X138795Y74500D01*
X140405D01*
G01X147600Y74400D02*
X141400D01*
Y77600D01*
X147600D01*
Y74400D01*
G01X131500Y90383D02*
X128400D01*
Y91342D01*
X128555Y91648D01*
X128762Y91840D01*
X129175Y91917D01*
X129588Y91840D01*
X129847Y91610D01*
X130002Y91342D01*
Y90383D01*
G01Y91342D02*
X131500Y91917D01*
G01X131035Y93407D02*
X131293Y93637D01*
X131448Y93905D01*
X131500Y94250D01*
X131397Y94595D01*
X131190Y94863D01*
X130828Y95055D01*
X130415Y95093D01*
X130002Y95017D01*
X129743Y94825D01*
X129537Y94557D01*
X129485Y94288D01*
X129537Y94020D01*
X129743Y93675D01*
X128400Y93790D01*
Y94825D01*
G01X128917Y96622D02*
X128607Y96852D01*
X128452Y97120D01*
X128400Y97427D01*
X128503Y97810D01*
X128762Y98078D01*
X129072Y98155D01*
X129382Y98117D01*
X129640Y97963D01*
X130157Y97197D01*
X130518Y96852D01*
X131035Y96622D01*
X131500Y96545D01*
Y98155D01*
G01X127721Y96792D02*
Y90592D01*
X124521D01*
Y96792D01*
X127721D01*
G01X141400Y105600D02*
X147600D01*
Y102400D01*
X141400D01*
Y105600D01*
G01X132633Y94500D02*
Y97600D01*
X133592D01*
X133898Y97445D01*
X134090Y97238D01*
X134167Y96825D01*
X134090Y96412D01*
X133860Y96153D01*
X133592Y95998D01*
X132633D01*
G01X133592D02*
X134167Y94500D01*
G01X135657Y95120D02*
X135887Y94758D01*
X136193Y94552D01*
X136538Y94500D01*
X136845Y94552D01*
X137152Y94810D01*
X137343Y95120D01*
X137382Y95430D01*
X137305Y95792D01*
X137037Y96050D01*
X136768Y96153D01*
X136423D01*
G01X136768D02*
X136998Y96308D01*
X137190Y96567D01*
X137267Y96877D01*
X137190Y97187D01*
X136998Y97445D01*
X136653Y97600D01*
X136308Y97548D01*
X135963Y97342D01*
G01X138948Y94862D02*
X139217Y94603D01*
X139523Y94500D01*
X139830Y94603D01*
X140098Y94913D01*
X140290Y95378D01*
X140367Y95843D01*
Y96412D01*
X140290Y96877D01*
X140098Y97290D01*
X139868Y97497D01*
X139600Y97600D01*
X139293Y97497D01*
X139063Y97290D01*
X138910Y96980D01*
X138833Y96567D01*
X138910Y96205D01*
X139102Y95843D01*
X139332Y95637D01*
X139600Y95585D01*
X139907Y95688D01*
X140137Y95947D01*
X140367Y96412D01*
G01X141400Y97600D02*
X147600D01*
Y94400D01*
X141400D01*
Y97600D01*
G01X147600Y106400D02*
X141400D01*
Y109600D01*
X147600D01*
Y106400D01*
G01Y98400D02*
X141400D01*
Y101600D01*
X147600D01*
Y98400D01*
G01X147500Y116500D02*
Y110500D01*
X135500D01*
Y116500D01*
X147500D01*
G01Y130500D02*
Y124500D01*
X135500D01*
Y130500D01*
X147500D01*
G01Y123500D02*
Y117500D01*
X135500D01*
Y123500D01*
X147500D01*
G01Y137500D02*
Y131500D01*
X135500D01*
Y137500D01*
X147500D01*
G01X143466Y147928D02*
G03I-9450J0D01*
G01X125493Y160842D02*
X125263Y160997D01*
X124995Y161100D01*
X124688D01*
X124343Y160945D01*
X124075Y160687D01*
X123883Y160377D01*
X123730Y159860D01*
X123692Y159395D01*
X123768Y158930D01*
X123883Y158620D01*
X124113Y158310D01*
X124382Y158103D01*
X124650Y158000D01*
X124918D01*
X125187Y158103D01*
X125417Y158258D01*
X125608Y158465D01*
G01X127750Y158000D02*
Y161100D01*
X127290Y160480D01*
G01Y158000D02*
X128210D01*
G01X130007Y158465D02*
X130237Y158207D01*
X130505Y158052D01*
X130850Y158000D01*
X131195Y158103D01*
X131463Y158310D01*
X131655Y158672D01*
X131693Y159085D01*
X131617Y159498D01*
X131425Y159757D01*
X131157Y159963D01*
X130888Y160015D01*
X130620Y159963D01*
X130275Y159757D01*
X130390Y161100D01*
X131425D01*
G01X137145Y158450D02*
Y161550D01*
G01X138755D02*
Y158450D01*
G01Y160000D02*
X137145D01*
G01X140207Y159070D02*
X140437Y158708D01*
X140743Y158502D01*
X141088Y158450D01*
X141395Y158502D01*
X141702Y158760D01*
X141893Y159070D01*
X141932Y159380D01*
X141855Y159742D01*
X141587Y160000D01*
X141318Y160103D01*
X140973D01*
G01X141318D02*
X141548Y160258D01*
X141740Y160517D01*
X141817Y160827D01*
X141740Y161137D01*
X141548Y161395D01*
X141203Y161550D01*
X140858Y161498D01*
X140513Y161292D01*
G01X125493Y164842D02*
X125263Y164997D01*
X124995Y165100D01*
X124688D01*
X124343Y164945D01*
X124075Y164687D01*
X123883Y164377D01*
X123730Y163860D01*
X123692Y163395D01*
X123768Y162930D01*
X123883Y162620D01*
X124113Y162310D01*
X124382Y162103D01*
X124650Y162000D01*
X124918D01*
X125187Y162103D01*
X125417Y162258D01*
X125608Y162465D01*
G01X127750Y162000D02*
Y165100D01*
X127290Y164480D01*
G01Y162000D02*
X128210D01*
G01X131310D02*
Y165100D01*
X129892Y162878D01*
X131808D01*
G01X142345Y276500D02*
Y279600D01*
G01X143955D02*
Y276500D01*
G01Y278050D02*
X142345D01*
G01X146250Y276500D02*
Y279600D01*
X145790Y278980D01*
G01Y276500D02*
X146710D01*
G01X149350Y279600D02*
X149043Y279497D01*
X148813Y279238D01*
X148660Y278928D01*
X148545Y278515D01*
X148507Y278050D01*
X148545Y277585D01*
X148660Y277172D01*
X148813Y276862D01*
X149043Y276603D01*
X149350Y276500D01*
X149657Y276603D01*
X149887Y276862D01*
X150040Y277172D01*
X150155Y277585D01*
X150193Y278050D01*
X150155Y278515D01*
X150040Y278928D01*
X149887Y279238D01*
X149657Y279497D01*
X149350Y279600D01*
G01X145559Y280500D02*
X139559D01*
G01Y308059D02*
X145559D01*
G01X145345Y26000D02*
Y29100D01*
G01X146955D02*
Y26000D01*
G01Y27550D02*
X145345D01*
G01X149250Y26000D02*
Y29100D01*
X148790Y28480D01*
G01Y26000D02*
X149710D01*
G01X152350D02*
Y29100D01*
X151890Y28480D01*
G01Y26000D02*
X152810D01*
G01X152469Y57205D02*
Y43425D01*
G01X146493Y141842D02*
X146263Y141997D01*
X145995Y142100D01*
X145688D01*
X145343Y141945D01*
X145075Y141687D01*
X144883Y141377D01*
X144730Y140860D01*
X144692Y140395D01*
X144768Y139930D01*
X144883Y139620D01*
X145113Y139310D01*
X145382Y139103D01*
X145650Y139000D01*
X145918D01*
X146187Y139103D01*
X146417Y139258D01*
X146608Y139465D01*
G01X148098Y139362D02*
X148367Y139103D01*
X148673Y139000D01*
X148980Y139103D01*
X149248Y139413D01*
X149440Y139878D01*
X149517Y140343D01*
Y140912D01*
X149440Y141377D01*
X149248Y141790D01*
X149018Y141997D01*
X148750Y142100D01*
X148443Y141997D01*
X148213Y141790D01*
X148060Y141480D01*
X147983Y141067D01*
X148060Y140705D01*
X148252Y140343D01*
X148482Y140137D01*
X148750Y140085D01*
X149057Y140188D01*
X149287Y140447D01*
X149517Y140912D01*
G01X146493Y150342D02*
X146263Y150497D01*
X145995Y150600D01*
X145688D01*
X145343Y150445D01*
X145075Y150187D01*
X144883Y149877D01*
X144730Y149360D01*
X144692Y148895D01*
X144768Y148430D01*
X144883Y148120D01*
X145113Y147810D01*
X145382Y147603D01*
X145650Y147500D01*
X145918D01*
X146187Y147603D01*
X146417Y147758D01*
X146608Y147965D01*
G01X148750Y147500D02*
Y150600D01*
X148290Y149980D01*
G01Y147500D02*
X149210D01*
G01X151122Y150083D02*
X151352Y150393D01*
X151620Y150548D01*
X151927Y150600D01*
X152310Y150497D01*
X152578Y150238D01*
X152655Y149928D01*
X152617Y149618D01*
X152463Y149360D01*
X151697Y148843D01*
X151352Y148482D01*
X151122Y147965D01*
X151045Y147500D01*
X152655D01*
G01X146493Y146342D02*
X146263Y146497D01*
X145995Y146600D01*
X145688D01*
X145343Y146445D01*
X145075Y146187D01*
X144883Y145877D01*
X144730Y145360D01*
X144692Y144895D01*
X144768Y144430D01*
X144883Y144120D01*
X145113Y143810D01*
X145382Y143603D01*
X145650Y143500D01*
X145918D01*
X146187Y143603D01*
X146417Y143758D01*
X146608Y143965D01*
G01X148750Y143500D02*
Y146600D01*
X148290Y145980D01*
G01Y143500D02*
X149210D01*
G01X151850Y146600D02*
X151543Y146497D01*
X151313Y146238D01*
X151160Y145928D01*
X151045Y145515D01*
X151007Y145050D01*
X151045Y144585D01*
X151160Y144172D01*
X151313Y143862D01*
X151543Y143603D01*
X151850Y143500D01*
X152157Y143603D01*
X152387Y143862D01*
X152540Y144172D01*
X152655Y144585D01*
X152693Y145050D01*
X152655Y145515D01*
X152540Y145928D01*
X152387Y146238D01*
X152157Y146497D01*
X151850Y146600D01*
G01X146493Y154342D02*
X146263Y154497D01*
X145995Y154600D01*
X145688D01*
X145343Y154445D01*
X145075Y154187D01*
X144883Y153877D01*
X144730Y153360D01*
X144692Y152895D01*
X144768Y152430D01*
X144883Y152120D01*
X145113Y151810D01*
X145382Y151603D01*
X145650Y151500D01*
X145918D01*
X146187Y151603D01*
X146417Y151758D01*
X146608Y151965D01*
G01X148750Y151500D02*
Y154600D01*
X148290Y153980D01*
G01Y151500D02*
X149210D01*
G01X151122Y152792D02*
X151390Y153153D01*
X151620Y153360D01*
X151927Y153463D01*
X152195Y153360D01*
X152387Y153153D01*
X152540Y152843D01*
X152578Y152482D01*
X152540Y152172D01*
X152387Y151862D01*
X152157Y151603D01*
X151888Y151500D01*
X151582Y151603D01*
X151313Y151913D01*
X151160Y152378D01*
X151122Y152895D01*
X151198Y153567D01*
X151313Y153928D01*
X151505Y154290D01*
X151773Y154548D01*
X152042Y154600D01*
X152310Y154497D01*
X152502Y154238D01*
G01X152058Y225945D02*
G03X160630Y247543I-22925J21599D01*
G01X145559Y286500D02*
Y280500D01*
G01Y308059D02*
Y302059D01*
G01X203432Y-313568D02*
X204032Y-312768D01*
X204732Y-312368D01*
X205532Y-312235D01*
X206532Y-312502D01*
X207232Y-313168D01*
X207432Y-313968D01*
X207332Y-314769D01*
X206932Y-315435D01*
X204932Y-316768D01*
X204032Y-317702D01*
X203432Y-319035D01*
X203232Y-320235D01*
X207432D01*
G01X213332Y-312235D02*
X212532Y-312502D01*
X211932Y-313168D01*
X211532Y-313968D01*
X211232Y-315035D01*
X211132Y-316235D01*
X211232Y-317435D01*
X211532Y-318502D01*
X211932Y-319302D01*
X212532Y-319968D01*
X213332Y-320235D01*
X214132Y-319968D01*
X214732Y-319302D01*
X215132Y-318502D01*
X215432Y-317435D01*
X215532Y-316235D01*
X215432Y-315035D01*
X215132Y-313968D01*
X214732Y-313168D01*
X214132Y-312502D01*
X213332Y-312235D01*
G01X219432Y-313568D02*
X220032Y-312768D01*
X220732Y-312368D01*
X221532Y-312235D01*
X222532Y-312502D01*
X223232Y-313168D01*
X223432Y-313968D01*
X223332Y-314769D01*
X222932Y-315435D01*
X220932Y-316768D01*
X220032Y-317702D01*
X219432Y-319035D01*
X219232Y-320235D01*
X223432D01*
G01X227432Y-313568D02*
X228032Y-312768D01*
X228732Y-312368D01*
X229532Y-312235D01*
X230532Y-312502D01*
X231232Y-313168D01*
X231432Y-313968D01*
X231332Y-314769D01*
X230932Y-315435D01*
X228932Y-316768D01*
X228032Y-317702D01*
X227432Y-319035D01*
X227232Y-320235D01*
X231432D01*
G01X235532Y-320502D02*
X239132Y-312235D01*
G01X245332Y-320235D02*
Y-312235D01*
X244132Y-313835D01*
G01Y-320235D02*
X246532D01*
G01X251432Y-313568D02*
X252032Y-312768D01*
X252732Y-312368D01*
X253532Y-312235D01*
X254532Y-312502D01*
X255232Y-313168D01*
X255432Y-313968D01*
X255332Y-314769D01*
X254932Y-315435D01*
X252932Y-316768D01*
X252032Y-317702D01*
X251432Y-319035D01*
X251232Y-320235D01*
X255432D01*
G01X259532Y-320502D02*
X263132Y-312235D01*
G01X269332D02*
X268532Y-312502D01*
X267932Y-313168D01*
X267532Y-313968D01*
X267232Y-315035D01*
X267132Y-316235D01*
X267232Y-317435D01*
X267532Y-318502D01*
X267932Y-319302D01*
X268532Y-319968D01*
X269332Y-320235D01*
X270132Y-319968D01*
X270732Y-319302D01*
X271132Y-318502D01*
X271432Y-317435D01*
X271532Y-316235D01*
X271432Y-315035D01*
X271132Y-313968D01*
X270732Y-313168D01*
X270132Y-312502D01*
X269332Y-312235D01*
G01X275632Y-319302D02*
X276332Y-319968D01*
X277132Y-320235D01*
X277932Y-319968D01*
X278632Y-319169D01*
X279132Y-317968D01*
X279332Y-316768D01*
Y-315302D01*
X279132Y-314102D01*
X278632Y-313035D01*
X278032Y-312502D01*
X277332Y-312235D01*
X276532Y-312502D01*
X275932Y-313035D01*
X275532Y-313835D01*
X275332Y-314902D01*
X275532Y-315835D01*
X276032Y-316768D01*
X276632Y-317302D01*
X277332Y-317435D01*
X278132Y-317169D01*
X278732Y-316502D01*
X279332Y-315302D01*
G01X205632Y-295235D02*
Y-287235D01*
X207632D01*
X208432Y-287635D01*
X209032Y-288168D01*
X209532Y-288968D01*
X209932Y-289902D01*
X210032Y-291235D01*
X209932Y-292568D01*
X209532Y-293502D01*
X209032Y-294302D01*
X208432Y-294835D01*
X207632Y-295235D01*
X205632D01*
G01X213332D02*
X215832Y-287235D01*
X218332Y-295235D01*
G01X217432Y-292435D02*
X214232D01*
G01X223832Y-287235D02*
X223032Y-287502D01*
X222432Y-288168D01*
X222032Y-288968D01*
X221732Y-290035D01*
X221632Y-291235D01*
X221732Y-292435D01*
X222032Y-293502D01*
X222432Y-294302D01*
X223032Y-294968D01*
X223832Y-295235D01*
X224632Y-294968D01*
X225232Y-294302D01*
X225632Y-293502D01*
X225932Y-292435D01*
X226032Y-291235D01*
X225932Y-290035D01*
X225632Y-288968D01*
X225232Y-288168D01*
X224632Y-287502D01*
X223832Y-287235D01*
G01X229932Y-295235D02*
Y-287235D01*
X233732D01*
G01X232332Y-291102D02*
X229932D01*
G01X239832Y-287235D02*
X239032Y-287502D01*
X238432Y-288168D01*
X238032Y-288968D01*
X237732Y-290035D01*
X237632Y-291235D01*
X237732Y-292435D01*
X238032Y-293502D01*
X238432Y-294302D01*
X239032Y-294968D01*
X239832Y-295235D01*
X240632Y-294968D01*
X241232Y-294302D01*
X241632Y-293502D01*
X241932Y-292435D01*
X242032Y-291235D01*
X241932Y-290035D01*
X241632Y-288968D01*
X241232Y-288168D01*
X240632Y-287502D01*
X239832Y-287235D01*
G01X247832D02*
Y-295235D01*
G01X245532Y-287235D02*
X250132D01*
G01X255832Y-295235D02*
Y-291635D01*
X253832Y-287235D01*
G01X257832D02*
X255832Y-291635D01*
G01X264632Y-290968D02*
X265032Y-290568D01*
X265332Y-289902D01*
X265532Y-288968D01*
X265332Y-288168D01*
X264932Y-287635D01*
X264232Y-287235D01*
X261532D01*
Y-295235D01*
X264832D01*
X265532Y-294702D01*
X265932Y-293902D01*
X266132Y-292968D01*
X265932Y-292035D01*
X265332Y-291235D01*
X264632Y-290968D01*
X261532D01*
G01X273032Y-295235D02*
Y-287235D01*
X269332Y-292968D01*
X274332D01*
G01X277632Y-295235D02*
Y-287235D01*
X279632D01*
X280432Y-287635D01*
X281032Y-288168D01*
X281532Y-288968D01*
X281932Y-289902D01*
X282032Y-291235D01*
X281932Y-292568D01*
X281532Y-293502D01*
X281032Y-294302D01*
X280432Y-294835D01*
X279632Y-295235D01*
X277632D01*
G01X287832Y-287235D02*
X287032Y-287502D01*
X286432Y-288168D01*
X286032Y-288968D01*
X285732Y-290035D01*
X285632Y-291235D01*
X285732Y-292435D01*
X286032Y-293502D01*
X286432Y-294302D01*
X287032Y-294968D01*
X287832Y-295235D01*
X288632Y-294968D01*
X289232Y-294302D01*
X289632Y-293502D01*
X289932Y-292435D01*
X290032Y-291235D01*
X289932Y-290035D01*
X289632Y-288968D01*
X289232Y-288168D01*
X288632Y-287502D01*
X287832Y-287235D01*
G01X233432Y-270235D02*
Y-262235D01*
X237232D01*
G01X235832Y-266102D02*
X233432D01*
G01X243332Y-262235D02*
X242532Y-262502D01*
X241932Y-263168D01*
X241532Y-263968D01*
X241232Y-265035D01*
X241132Y-266235D01*
X241232Y-267435D01*
X241532Y-268502D01*
X241932Y-269302D01*
X242532Y-269968D01*
X243332Y-270235D01*
X244132Y-269968D01*
X244732Y-269302D01*
X245132Y-268502D01*
X245432Y-267435D01*
X245532Y-266235D01*
X245432Y-265035D01*
X245132Y-263968D01*
X244732Y-263168D01*
X244132Y-262502D01*
X243332Y-262235D01*
G01X251332D02*
Y-270235D01*
G01X249032Y-262235D02*
X253632D01*
G01X256332Y-272902D02*
X262332D01*
G01X265332Y-270235D02*
Y-262235D01*
X267732D01*
X268532Y-262635D01*
X269132Y-263568D01*
X269332Y-264635D01*
X269132Y-265702D01*
X268632Y-266502D01*
X267732Y-266902D01*
X265332D01*
G01X272832Y-270235D02*
X275332Y-262235D01*
X277832Y-270235D01*
G01X276932Y-267435D02*
X273732D01*
G01X281032Y-270235D02*
Y-262235D01*
X285632Y-270235D01*
Y-262235D01*
G01X293332Y-270235D02*
X289332D01*
Y-262235D01*
X293332D01*
G01X291732Y-266102D02*
X289332D01*
G01X297332Y-262235D02*
Y-270235D01*
X301332D01*
G01X304332Y-272902D02*
X310332D01*
G01X316132Y-265968D02*
X316532Y-265568D01*
X316832Y-264902D01*
X317032Y-263968D01*
X316832Y-263168D01*
X316432Y-262635D01*
X315732Y-262235D01*
X313032D01*
Y-270235D01*
X316332D01*
X317032Y-269702D01*
X317432Y-268902D01*
X317632Y-267968D01*
X317432Y-267035D01*
X316832Y-266235D01*
X316132Y-265968D01*
X313032D01*
G01X321132Y-270235D02*
Y-262235D01*
X323132D01*
X323932Y-262635D01*
X324532Y-263168D01*
X325032Y-263968D01*
X325432Y-264902D01*
X325532Y-266235D01*
X325432Y-267568D01*
X325032Y-268502D01*
X324532Y-269302D01*
X323932Y-269835D01*
X323132Y-270235D01*
X321132D01*
G01X291832Y-323235D02*
Y-315235D01*
X290632Y-316835D01*
G01Y-323235D02*
X293032D01*
G01X297932Y-319902D02*
X298632Y-318968D01*
X299232Y-318435D01*
X300032Y-318168D01*
X300732Y-318435D01*
X301232Y-318968D01*
X301632Y-319768D01*
X301732Y-320702D01*
X301632Y-321502D01*
X301232Y-322302D01*
X300632Y-322968D01*
X299932Y-323235D01*
X299132Y-322968D01*
X298432Y-322169D01*
X298032Y-320968D01*
X297932Y-319635D01*
X298132Y-317902D01*
X298432Y-316968D01*
X298932Y-316035D01*
X299632Y-315368D01*
X300332Y-315235D01*
X301032Y-315502D01*
X301532Y-316168D01*
G01X307832Y-323502D02*
X307632Y-323368D01*
Y-323102D01*
X307832Y-322968D01*
X308032Y-323102D01*
Y-323368D01*
X307832Y-323502D01*
G01X313932Y-319902D02*
X314632Y-318968D01*
X315232Y-318435D01*
X316032Y-318168D01*
X316732Y-318435D01*
X317232Y-318968D01*
X317632Y-319768D01*
X317732Y-320702D01*
X317632Y-321502D01*
X317232Y-322302D01*
X316632Y-322968D01*
X315932Y-323235D01*
X315132Y-322968D01*
X314432Y-322169D01*
X314032Y-320968D01*
X313932Y-319635D01*
X314132Y-317902D01*
X314432Y-316968D01*
X314932Y-316035D01*
X315632Y-315368D01*
X316332Y-315235D01*
X317032Y-315502D01*
X317532Y-316168D01*
G01X336832Y-323235D02*
Y-315235D01*
X335632Y-316835D01*
G01Y-323235D02*
X338032D01*
G01X344632D02*
X344832Y-321502D01*
X345132Y-320035D01*
X345532Y-318702D01*
X346032Y-317235D01*
X346832Y-315235D01*
X342832D01*
G01X352832Y-323502D02*
X352632Y-323368D01*
Y-323102D01*
X352832Y-322968D01*
X353032Y-323102D01*
Y-323368D01*
X352832Y-323502D01*
G01X358932Y-316568D02*
X359532Y-315768D01*
X360232Y-315368D01*
X361032Y-315235D01*
X362032Y-315502D01*
X362732Y-316168D01*
X362932Y-316968D01*
X362832Y-317769D01*
X362432Y-318435D01*
X360432Y-319768D01*
X359532Y-320702D01*
X358932Y-322035D01*
X358732Y-323235D01*
X362932D01*
G01X333383Y85620D02*
X333575Y85310D01*
X333805Y85103D01*
X334073Y85000D01*
X334380Y85103D01*
X334610Y85310D01*
X334840Y85620D01*
X334917Y86033D01*
Y88100D01*
G01X337710Y85000D02*
Y88100D01*
X336292Y85878D01*
X338208D01*
G01X331824Y110512D02*
X358050D01*
X344937Y75936D01*
X331824Y110512D01*
G01X360146Y228925D02*
X333920D01*
X347033Y263501D01*
X360146Y228925D01*
G01X356632Y-298235D02*
Y-290235D01*
X358632D01*
X359432Y-290635D01*
X360032Y-291168D01*
X360532Y-291968D01*
X360932Y-292902D01*
X361032Y-294235D01*
X360932Y-295568D01*
X360532Y-296502D01*
X360032Y-297302D01*
X359432Y-297835D01*
X358632Y-298235D01*
X356632D01*
G01X337383Y255120D02*
X337575Y254810D01*
X337805Y254603D01*
X338073Y254500D01*
X338380Y254603D01*
X338610Y254810D01*
X338840Y255120D01*
X338917Y255533D01*
Y257600D01*
G01X340407Y255120D02*
X340637Y254758D01*
X340943Y254552D01*
X341288Y254500D01*
X341595Y254552D01*
X341902Y254810D01*
X342093Y255120D01*
X342132Y255430D01*
X342055Y255792D01*
X341787Y256050D01*
X341518Y256153D01*
X341173D01*
G01X341518D02*
X341748Y256308D01*
X341940Y256567D01*
X342017Y256877D01*
X341940Y257187D01*
X341748Y257445D01*
X341403Y257600D01*
X341058Y257548D01*
X340713Y257342D01*
G01X342963Y413150D02*
X343155Y412840D01*
X343385Y412633D01*
X343653Y412530D01*
X343960Y412633D01*
X344190Y412840D01*
X344420Y413150D01*
X344497Y413563D01*
Y415630D01*
G01X345987Y412995D02*
X346217Y412737D01*
X346485Y412582D01*
X346830Y412530D01*
X347175Y412633D01*
X347443Y412840D01*
X347635Y413202D01*
X347673Y413615D01*
X347597Y414028D01*
X347405Y414287D01*
X347137Y414493D01*
X346868Y414545D01*
X346600Y414493D01*
X346255Y414287D01*
X346370Y415630D01*
X347405D01*
G01X337200Y436300D02*
X353800D01*
Y426700D01*
X337200D01*
Y436300D01*
G01X353800Y606200D02*
X337200D01*
Y615800D01*
X353800D01*
Y606200D01*
G01X343533Y627090D02*
X343725Y626780D01*
X343955Y626573D01*
X344223Y626470D01*
X344530Y626573D01*
X344760Y626780D01*
X344990Y627090D01*
X345067Y627503D01*
Y629570D01*
G01X346672Y627762D02*
X346940Y628123D01*
X347170Y628330D01*
X347477Y628433D01*
X347745Y628330D01*
X347937Y628123D01*
X348090Y627813D01*
X348128Y627452D01*
X348090Y627142D01*
X347937Y626832D01*
X347707Y626573D01*
X347438Y626470D01*
X347132Y626573D01*
X346863Y626883D01*
X346710Y627348D01*
X346672Y627865D01*
X346748Y628537D01*
X346863Y628898D01*
X347055Y629260D01*
X347323Y629518D01*
X347592Y629570D01*
X347860Y629467D01*
X348052Y629208D01*
G01X367695Y93000D02*
X365195D01*
Y83000D01*
X365745D01*
G01X374645D02*
X375745D01*
G01X377695Y93000D02*
X372695D01*
G01X363345Y263500D02*
X364955Y266600D01*
G01X363345D02*
X364955Y263500D01*
G01X367250D02*
Y266600D01*
X366790Y265980D01*
G01Y263500D02*
X367710D01*
G01X375745Y257618D02*
X374645D01*
G01X365745D02*
X365195D01*
Y247618D01*
G01X372695D02*
X377695D01*
G01X365195D02*
X367695D01*
G01X372188Y310365D02*
X372380Y310055D01*
X372610Y309848D01*
X372878Y309745D01*
X373185Y309848D01*
X373415Y310055D01*
X373645Y310365D01*
X373722Y310778D01*
Y312845D01*
G01X376055Y309745D02*
X376323Y309797D01*
X376630Y309952D01*
X376822Y310210D01*
X376898Y310572D01*
X376822Y310933D01*
X376592Y311243D01*
X376247Y311398D01*
X375863D01*
X375633Y311502D01*
X375442Y311760D01*
X375365Y312122D01*
X375480Y312483D01*
X375748Y312742D01*
X376055Y312845D01*
X376362Y312742D01*
X376630Y312483D01*
X376745Y312122D01*
X376668Y311760D01*
X376477Y311502D01*
X376247Y311398D01*
X375863D01*
X375518Y311243D01*
X375288Y310933D01*
X375212Y310572D01*
X375288Y310210D01*
X375480Y309952D01*
X375787Y309797D01*
X376055Y309745D01*
G01X366700Y332486D02*
X383300D01*
Y322886D01*
X366700D01*
Y332486D01*
G01X383300Y606200D02*
X366700D01*
Y615800D01*
X383300D01*
Y606200D01*
G01X373243Y626980D02*
X373435Y626670D01*
X373665Y626463D01*
X373933Y626360D01*
X374240Y626463D01*
X374470Y626670D01*
X374700Y626980D01*
X374777Y627393D01*
Y629460D01*
G01X377033Y626360D02*
X377110Y627032D01*
X377225Y627600D01*
X377378Y628117D01*
X377570Y628685D01*
X377877Y629460D01*
X376343D01*
G01X379345Y73500D02*
X380955Y76600D01*
G01X379345D02*
X380955Y73500D01*
G01X382522Y76083D02*
X382752Y76393D01*
X383020Y76548D01*
X383327Y76600D01*
X383710Y76497D01*
X383978Y76238D01*
X384055Y75928D01*
X384017Y75618D01*
X383863Y75360D01*
X383097Y74843D01*
X382752Y74482D01*
X382522Y73965D01*
X382445Y73500D01*
X384055D01*
G01X384645Y83000D02*
X385195D01*
Y93000D01*
G01D02*
X382695D01*
G01Y247618D02*
X385195D01*
Y257618D01*
X384645D01*
G01X384500Y644307D02*
X381400D01*
Y645073D01*
X381555Y645380D01*
X381762Y645610D01*
X382072Y645802D01*
X382433Y645955D01*
X382950Y645993D01*
X383467Y645955D01*
X383828Y645802D01*
X384138Y645610D01*
X384345Y645380D01*
X384500Y645073D01*
Y644307D01*
G01Y647292D02*
X381400Y648250D01*
X384500Y649208D01*
G01X383415Y648863D02*
Y647637D01*
G01X381400Y651350D02*
X381503Y651043D01*
X381762Y650813D01*
X382072Y650660D01*
X382485Y650545D01*
X382950Y650507D01*
X383415Y650545D01*
X383828Y650660D01*
X384138Y650813D01*
X384397Y651043D01*
X384500Y651350D01*
X384397Y651657D01*
X384138Y651887D01*
X383828Y652040D01*
X383415Y652155D01*
X382950Y652193D01*
X382485Y652155D01*
X382072Y652040D01*
X381762Y651887D01*
X381503Y651657D01*
X381400Y651350D01*
G01X384500Y653722D02*
X381400D01*
Y655178D01*
G01X382898Y654642D02*
Y653722D01*
G01X381400Y657550D02*
X381503Y657243D01*
X381762Y657013D01*
X382072Y656860D01*
X382485Y656745D01*
X382950Y656707D01*
X383415Y656745D01*
X383828Y656860D01*
X384138Y657013D01*
X384397Y657243D01*
X384500Y657550D01*
X384397Y657857D01*
X384138Y658087D01*
X383828Y658240D01*
X383415Y658355D01*
X382950Y658393D01*
X382485Y658355D01*
X382072Y658240D01*
X381762Y658087D01*
X381503Y657857D01*
X381400Y657550D01*
G01Y660650D02*
X384500D01*
G01X381400Y659768D02*
Y661532D01*
G01X384500Y663750D02*
X383105D01*
X381400Y662983D01*
G01Y664517D02*
X383105Y663750D01*
G01X382847Y667157D02*
X382692Y667310D01*
X382433Y667425D01*
X382072Y667502D01*
X381762Y667425D01*
X381555Y667272D01*
X381400Y667003D01*
Y665968D01*
X384500D01*
Y667233D01*
X384293Y667502D01*
X383983Y667655D01*
X383622Y667732D01*
X383260Y667655D01*
X382950Y667425D01*
X382847Y667157D01*
Y665968D01*
G01X384500Y670410D02*
X381400D01*
X383622Y668992D01*
Y670908D01*
G01X384500Y672207D02*
X381400D01*
Y672973D01*
X381555Y673280D01*
X381762Y673510D01*
X382072Y673702D01*
X382433Y673855D01*
X382950Y673893D01*
X383467Y673855D01*
X383828Y673702D01*
X384138Y673510D01*
X384345Y673280D01*
X384500Y672973D01*
Y672207D01*
G01X381400Y676150D02*
X381503Y675843D01*
X381762Y675613D01*
X382072Y675460D01*
X382485Y675345D01*
X382950Y675307D01*
X383415Y675345D01*
X383828Y675460D01*
X384138Y675613D01*
X384397Y675843D01*
X384500Y676150D01*
X384397Y676457D01*
X384138Y676687D01*
X383828Y676840D01*
X383415Y676955D01*
X382950Y676993D01*
X382485Y676955D01*
X382072Y676840D01*
X381762Y676687D01*
X381503Y676457D01*
X381400Y676150D01*
M02*
